G04 ================== begin FILE IDENTIFICATION RECORD ==================*
G04 Layout Name:  14545-sa.brd*
G04 Film Name:    L5VCC*
G04 File Format:  Gerber RS274X*
G04 File Origin:  Cadence Allegro 16.5-S056*
G04 Origin Date:  Fri Aug 01 17:58:49 2014*
G04 *
G04 Layer:  VIA CLASS/L5VCC*
G04 Layer:  PIN/L5VCC*
G04 Layer:  PACKAGE GEOMETRY/PWRVCC*
G04 Layer:  ETCH/L5VCC*
G04 Layer:  DRAWING FORMAT/LAYER_PCB_STORY*
G04 Layer:  DRAWING FORMAT/LAYER_L5VCC*
G04 *
G04 Offset:    (0.00 0.00)*
G04 Mirror:    No*
G04 Mode:      Negative*
G04 Rotation:  0*
G04 FullContactRelief:  No*
G04 UndefLineWidth:     6.00*
G04 ================== end FILE IDENTIFICATION RECORD ====================*
%FSLAX35Y35*MOIN*%
%IR0*IPPOS*OFA0.00000B0.00000*MIA0B0*SFA1.00000B1.00000*%
%ADD16O,.115X.072*%
%ADD14C,.032*%
%ADD11C,.036*%
%AMMACRO13*
4,1,15,.00398,.00044,
.003999,.000208,
.004004,-.000025,
.003996,-.000258,
.00398,-.00044,
.00483,-.00129,
.004897,-.001007,
.004947,-.000721,
.004981,-.000432,
.004997,-.000141,
.004997,.000149,
.00498,.00044,
.004946,.000729,
.004895,.001015,
.00483,.00129,
.00398,.00044,
0.0*
4,1,15,.00044,-.00398,
.000208,-.003999,
-.000025,-.004004,
-.000258,-.003996,
-.00044,-.00398,
-.00129,-.00483,
-.001007,-.004897,
-.000721,-.004947,
-.000432,-.004981,
-.000141,-.004997,
.000149,-.004997,
.00044,-.00498,
.000729,-.004946,
.001015,-.004895,
.00129,-.00483,
.00044,-.00398,
0.0*
4,1,15,-.00398,-.00044,
-.003999,-.000208,
-.004004,.000025,
-.003996,.000258,
-.00398,.00044,
-.00483,.00129,
-.004897,.001007,
-.004947,.000721,
-.004981,.000432,
-.004997,.000141,
-.004997,-.000149,
-.00498,-.00044,
-.004946,-.000729,
-.004895,-.001015,
-.00483,-.00129,
-.00398,-.00044,
0.0*
4,1,15,-.00044,.00398,
-.000208,.003999,
.000025,.004004,
.000258,.003996,
.00044,.00398,
.00129,.00483,
.001007,.004897,
.000721,.004947,
.000432,.004981,
.000141,.004997,
-.000149,.004997,
-.00044,.00498,
-.000729,.004946,
-.001015,.004895,
-.00129,.00483,
-.00044,.00398,
0.0*
%
%ADD13MACRO13*%
%ADD17C,.101*%
%ADD10C,.114*%
%ADD15C,.18*%
%ADD12C,.119*%
%ADD21C,.174*%
%ADD18C,.197*%
%AMMACRO20*
4,1,15,.00398,.00044,
.003999,.000208,
.004004,-.000025,
.003996,-.000258,
.00398,-.00044,
.00483,-.00129,
.004897,-.001007,
.004947,-.000721,
.004981,-.000432,
.004997,-.000141,
.004997,.000149,
.00498,.00044,
.004946,.000729,
.004895,.001015,
.00483,.00129,
.00398,.00044,
270.*
4,1,15,.00044,-.00398,
.000208,-.003999,
-.000025,-.004004,
-.000258,-.003996,
-.00044,-.00398,
-.00129,-.00483,
-.001007,-.004897,
-.000721,-.004947,
-.000432,-.004981,
-.000141,-.004997,
.000149,-.004997,
.00044,-.00498,
.000729,-.004946,
.001015,-.004895,
.00129,-.00483,
.00044,-.00398,
270.*
4,1,15,-.00398,-.00044,
-.003999,-.000208,
-.004004,.000025,
-.003996,.000258,
-.00398,.00044,
-.00483,.00129,
-.004897,.001007,
-.004947,.000721,
-.004981,.000432,
-.004997,.000141,
-.004997,-.000149,
-.00498,-.00044,
-.004946,-.000729,
-.004895,-.001015,
-.00483,-.00129,
-.00398,-.00044,
270.*
4,1,15,-.00044,.00398,
-.000208,.003999,
.000025,.004004,
.000258,.003996,
.00044,.00398,
.00129,.00483,
.001007,.004897,
.000721,.004947,
.000432,.004981,
.000141,.004997,
-.000149,.004997,
-.00044,.00498,
-.000729,.004946,
-.001015,.004895,
-.00129,.00483,
-.00044,.00398,
270.*
%
%ADD20MACRO20*%
%AMMACRO19*
4,1,15,.00398,.00044,
.003999,.000208,
.004004,-.000025,
.003996,-.000258,
.00398,-.00044,
.00483,-.00129,
.004897,-.001007,
.004947,-.000721,
.004981,-.000432,
.004997,-.000141,
.004997,.000149,
.00498,.00044,
.004946,.000729,
.004895,.001015,
.00483,.00129,
.00398,.00044,
180.*
4,1,15,.00044,-.00398,
.000208,-.003999,
-.000025,-.004004,
-.000258,-.003996,
-.00044,-.00398,
-.00129,-.00483,
-.001007,-.004897,
-.000721,-.004947,
-.000432,-.004981,
-.000141,-.004997,
.000149,-.004997,
.00044,-.00498,
.000729,-.004946,
.001015,-.004895,
.00129,-.00483,
.00044,-.00398,
180.*
4,1,15,-.00398,-.00044,
-.003999,-.000208,
-.004004,.000025,
-.003996,.000258,
-.00398,.00044,
-.00483,.00129,
-.004897,.001007,
-.004947,.000721,
-.004981,.000432,
-.004997,.000141,
-.004997,-.000149,
-.00498,-.00044,
-.004946,-.000729,
-.004895,-.001015,
-.00483,-.00129,
-.00398,-.00044,
180.*
4,1,15,-.00044,.00398,
-.000208,.003999,
.000025,.004004,
.000258,.003996,
.00044,.00398,
.00129,.00483,
.001007,.004897,
.000721,.004947,
.000432,.004981,
.000141,.004997,
-.000149,.004997,
-.00044,.00498,
-.000729,.004946,
-.001015,.004895,
-.00129,.00483,
-.00044,.00398,
180.*
%
%ADD19MACRO19*%
%ADD22C,.02*%
%ADD23C,.006*%
%ADD28C,.09704*%
%ADD27C,.11504*%
%ADD24O,.0802X.0462*%
%ADD29C,.17004*%
%ADD26O,.0812X.0462*%
%ADD25O,.0822X.0462*%
G75*
%LPD*%
G75*
G36*
G01X-6000Y-6000D02*
X1039465D01*
Y1998126D01*
X-6000D01*
Y-6000D01*
G37*
%LPC*%
G75*
G36*
G01X24206Y426804D02*
X24081Y423407D01*
X24083D01*
X24092Y423216D01*
G03X24111Y423005I2307J101D01*
G02X23797Y422814I-198J-28D01*
G03X19883Y424067I-3915J-5491D01*
G01X3213D01*
X3004Y424276D01*
Y819818D01*
X3213Y820027D01*
X19882D01*
G03Y833516I0J6745D01*
G01X3213D01*
X3004Y833725D01*
Y1194621D01*
X3214Y1194831D01*
X19882D01*
G03Y1208319I0J6744D01*
G01X3213D01*
X3004Y1208528D01*
Y1394621D01*
X3214Y1394831D01*
X19882D01*
G03Y1408319I0J6744D01*
G01X3213D01*
X3004Y1408528D01*
Y1804070D01*
X3213Y1804279D01*
X19882D01*
G03Y1817768I0J6744D01*
G01X3213D01*
X3004Y1817977D01*
Y1988189D01*
G02X3937Y1989122I933J0D01*
G01X1029528D01*
G02X1030461Y1988189I0J-933D01*
G01Y1686599D01*
X1028283Y1684421D01*
X1024211D01*
G03X1016287Y1676496I1J-7925D01*
G01Y1621265D01*
X1014109Y1619087D01*
X989744D01*
G03Y1608866I0J-5110D01*
G01X1014109D01*
X1016287Y1606688D01*
Y1433740D01*
G03X1024211Y1425815I7925J0D01*
G01X1028283D01*
X1030461Y1423637D01*
Y3937D01*
G02X1029528Y3004I-933J0D01*
G01X3937D01*
G02X3004Y3937I0J933D01*
G01Y210369D01*
X3214Y210579D01*
X19882D01*
G03Y224067I0J6744D01*
G01X3213D01*
X3004Y224276D01*
Y410369D01*
X3214Y410579D01*
X19882D01*
G03X25866Y420434I0J6744D01*
G02X26247Y421018I355J185D01*
G03X28694Y423060I152J2304D01*
G01X28714Y423237D01*
X28717D01*
X28842Y426635D01*
X28840D01*
X28831Y426826D01*
G03X24221Y426887I-2307J-106D01*
G01X24215Y426813D01*
X24206Y426804D01*
G37*
%LPD*%
G75*
G36*
G01X853512Y1873346D02*
G02X853485Y1868726I-14J-2310D01*
G01X850085Y1868746D01*
G02X850113Y1873366I14J2310D01*
G01X853512Y1873346D01*
G37*
G36*
G01X121083Y1870817D02*
X121080Y1870995D01*
X121077D01*
X121276Y1874390D01*
X121278D01*
X121305Y1874580D01*
G02X125902Y1874296I2287J-325D01*
G01X125905Y1874118D01*
X125908D01*
X125709Y1870724D01*
X125700Y1870715D01*
X125693Y1870643D01*
G02X121083Y1870817I-2300J216D01*
G37*
G36*
G01X869224Y1861839D02*
G02X864604Y1861840I-2310J1D01*
G01Y1865615D01*
G02X869224I2310J0D01*
G01Y1861839D01*
G37*
G36*
G01X140309Y1861496D02*
G02X135689Y1861497I-2310J1D01*
G01Y1865151D01*
G02X140309I2310J0D01*
G01Y1861496D01*
G37*
G36*
G01X82886Y1748948D02*
X83033Y1752344D01*
G02X87649Y1752145I2308J-99D01*
G01X87502Y1748748D01*
G02X82886Y1748948I-2308J100D01*
G37*
G36*
G01X107093Y1739419D02*
X107082Y1739608D01*
X107080D01*
X107180Y1743607D01*
X107189Y1743616D01*
X107194Y1743692D01*
G02X111805Y1743681I2305J-143D01*
G01X111816Y1743492D01*
X111818D01*
X111718Y1739492D01*
X111715D01*
X111696Y1739313D01*
G02X107093Y1739419I-2297J238D01*
G37*
G36*
G01X48187Y1724823D02*
G02X43567I-2310J0D01*
G01Y1728478D01*
G02X48187Y1728477I2310J-1D01*
G01Y1724823D01*
G37*
G36*
G01X29660Y1642692D02*
G02X29593Y1647312I-34J2310D01*
G01X32993Y1647361D01*
G02X33059Y1642741I33J-2310D01*
G01X29660Y1642692D01*
G37*
G36*
G01X30219Y1509592D02*
G02X30012Y1514208I-104J2308D01*
G01X33409Y1514359D01*
G02X33615Y1509743I103J-2308D01*
G01X30219Y1509592D01*
G37*
G36*
G01X852326Y1468656D02*
G02X852250Y1464036I-38J-2310D01*
G01X848851Y1464092D01*
G02X848926Y1468712I38J2310D01*
G01X852326Y1468656D01*
G37*
G36*
G01X30485Y1460210D02*
G02X30272Y1464826I-106J2308D01*
G01X33809Y1464989D01*
G02X34021Y1460373I106J-2308D01*
G01X30485Y1460210D01*
G37*
G36*
G01X875767Y1456129D02*
X875740Y1456319D01*
X875738D01*
X875537Y1459860D01*
X875540D01*
X875544Y1460038D01*
G02X880159Y1460121I2309J-48D01*
G01X880170Y1459922D01*
X880180D01*
X880370Y1456582D01*
X880362Y1456574D01*
X880363Y1456489D01*
G02X875767Y1456129I-2309J-39D01*
G37*
G36*
G01X140702Y1456131D02*
X140683Y1456310D01*
X140680D01*
X140581Y1459937D01*
X140583D01*
X140594Y1460126D01*
G02X145197Y1460242I2306J-127D01*
G01X145216Y1460063D01*
X145219D01*
X145318Y1456437D01*
X145310Y1456429D01*
X145309Y1456347D01*
G02X140702Y1456131I-2310J26D01*
G37*
G36*
G01X107245Y1440601D02*
G02X102625Y1440668I-2310J33D01*
G01X102689Y1444975D01*
G02X107309Y1444907I2310J-34D01*
G01X107245Y1440601D01*
G37*
G36*
G01X31903Y1430445D02*
X31745Y1430553D01*
X31744Y1430551D01*
X29037Y1432749D01*
X29039Y1432752D01*
X28910Y1432874D01*
G02X31955Y1436343I1590J1676D01*
G01X32110Y1436217D01*
X32116Y1436225D01*
X34668Y1434154D01*
Y1434142D01*
X34736Y1434083D01*
G02X31903Y1430445I-1529J-1732D01*
G37*
G36*
G01X119700Y1426200D02*
G02X115080Y1426201I-2310J1D01*
G01Y1429976D01*
G02X119700I2310J0D01*
G01Y1426200D01*
G37*
G36*
G01X31582Y1387198D02*
X31409Y1387257D01*
X31408Y1387255D01*
X27575Y1388922D01*
X27555Y1388942D01*
X27523Y1388957D01*
G02X29250Y1393235I977J2093D01*
G01X29423Y1393176D01*
X29424Y1393178D01*
X33258Y1391511D01*
X33257Y1391509D01*
X33421Y1391421D01*
G02X31582Y1387198I-1089J-2038D01*
G37*
G36*
G01X99536Y1373462D02*
G02X94922Y1373213I-2307J-125D01*
G01X94693Y1377476D01*
G02X99307Y1377724I2307J124D01*
G01X99536Y1373462D01*
G37*
G36*
G01X114719Y1357817D02*
G02X110161Y1358576I-2279J380D01*
G01X110720Y1361930D01*
G02X115278Y1361170I2279J-380D01*
G01X114719Y1357817D01*
G37*
G36*
G01X115810Y1344499D02*
G02X111190Y1344500I-2310J1D01*
G01Y1348154D01*
G02X115810I2310J0D01*
G01Y1344499D01*
G37*
G36*
G01X104660D02*
G02X100040Y1344500I-2310J1D01*
G01Y1348154D01*
G02X104660I2310J0D01*
G01Y1344499D01*
G37*
G36*
G01X111538Y1333315D02*
G02X106918I-2310J0D01*
G01Y1337091D01*
G02X111538Y1337090I2310J-1D01*
G01Y1333315D01*
G37*
G36*
G01X139791Y1077561D02*
G02X135171Y1077554I-2310J-3D01*
G01X135167Y1081174D01*
G02X139787Y1081180I2310J3D01*
G01Y1081174D01*
X139791Y1077561D01*
G37*
G36*
G01X126733Y1077522D02*
G02X122113Y1077523I-2310J1D01*
G01Y1081177D01*
G02X126733I2310J0D01*
G01Y1077522D01*
G37*
G36*
G01X850865Y1063751D02*
G02X850800Y1059131I-32J-2310D01*
G01X847200Y1059182D01*
G02X847266Y1063802I33J2310D01*
G01X850865Y1063751D01*
G37*
G36*
G01X880536Y1051279D02*
G02X875930Y1050912I-2303J-183D01*
G01X875661Y1054302D01*
G02X880267Y1054668I2303J183D01*
G01X880536Y1051279D01*
G37*
G36*
G01X126309Y1050650D02*
G02X121689I-2310J0D01*
G01Y1054051D01*
G02X126309Y1054050I2310J-1D01*
G01Y1050650D01*
G37*
G36*
G01X88693Y937322D02*
G02X84105Y936778I-2294J-272D01*
G01X83705Y940156D01*
G02X88293Y940701I2294J272D01*
G01X88693Y937322D01*
G37*
G36*
G01X111403Y928423D02*
G02X106795Y928078I-2304J-173D01*
G01X106541Y931485D01*
G02X111149Y931829I2304J172D01*
G01X111403Y928423D01*
G37*
G36*
G01X29997Y667446D02*
G02X25377Y667447I-2310J1D01*
G01Y671101D01*
G02X29997I2310J0D01*
G01Y667446D01*
G37*
G36*
G01X847814Y653060D02*
G02X847730Y657680I-42J2310D01*
G01X851129Y657742D01*
G02X851214Y653122I42J-2310D01*
G01X847814Y653060D01*
G37*
G36*
G01X880906Y645572D02*
G02X876286Y645573I-2310J1D01*
G01Y649348D01*
G02X880906I2310J0D01*
G01Y645572D01*
G37*
G36*
G01X146548Y645355D02*
G02X141928Y645356I-2310J1D01*
G01Y649131D01*
G02X146548I2310J0D01*
G01Y645355D01*
G37*
G36*
G01X132021Y646825D02*
G02X130779Y642375I-621J-2225D01*
G01X127409Y643317D01*
X127408D01*
G02X128620Y647775I591J2233D01*
G01X132021Y646825D01*
G37*
G36*
G01X127809Y635549D02*
G02X123189Y635550I-2310J1D01*
G01Y638950D01*
G02X127809I2310J0D01*
G01Y635549D01*
G37*
G36*
G01X57689Y537547D02*
G02X62309Y537553I2310J3D01*
G01Y537547D01*
X62313Y534154D01*
G02X57693Y534147I-2310J-3D01*
G01X57689Y537547D01*
G37*
G36*
G01X88509Y532249D02*
G02X83889Y532250I-2310J1D01*
G01Y536025D01*
G02X88509I2310J0D01*
G01Y532249D01*
G37*
G36*
G01X28909Y525647D02*
G02X24289Y525648I-2310J1D01*
G01Y529302D01*
G02X28909I2310J0D01*
G01Y525647D01*
G37*
G36*
G01X38809Y517774D02*
G02X34189Y517775I-2310J1D01*
G01Y521550D01*
G02X38809I2310J0D01*
G01Y517774D01*
G37*
G36*
G01X28709Y501965D02*
G02X24089Y501966I-2310J1D01*
G01Y505741D01*
G02X28709I2310J0D01*
G01Y501965D01*
G37*
G36*
G01X62291Y486368D02*
X62391Y489768D01*
G02X67009Y489632I2309J-68D01*
G01X66909Y486244D01*
G02X62291Y486368I-2309J56D01*
G37*
G36*
G01X23990Y478372D02*
X23987Y478551D01*
X23984D01*
X24200Y481945D01*
X24202D01*
X24230Y482134D01*
G02X28824Y481830I2285J-337D01*
G01X28827Y481651D01*
X28830D01*
X28614Y478258D01*
X28604Y478248D01*
X28597Y478177D01*
G02X23990Y478372I-2298J227D01*
G37*
G36*
G01X62087Y474442D02*
G02X66707Y474450I2310J4D01*
G01Y474442D01*
X66713Y471051D01*
G02X62093Y471042I-2310J-5D01*
G01X62087Y474442D01*
G37*
G36*
G01X25191Y460155D02*
G03X25145Y460767I-279J287D01*
G02X24176Y462656I1341J1881D01*
G01X24189Y466258D01*
G02X28809Y466242I2310J-8D01*
G01X28796Y462641D01*
G02X28094Y460990I-2310J7D01*
G03X28140Y460378I279J-287D01*
G02X29096Y458740I-1341J-1881D01*
G01X29115Y458561D01*
X29118D01*
X29218Y454915D01*
X29210Y454907D01*
X29209Y454825D01*
G02X24602Y454607I-2310J24D01*
G01X24583Y454786D01*
X24580D01*
X24480Y458433D01*
X24482D01*
X24493Y458622D01*
G02X25191Y460155I2306J-125D01*
G37*
G36*
G01X28801Y439278D02*
G02X24183Y439423I-2309J73D01*
G01X24290Y442822D01*
G02X28908Y442676I2309J-73D01*
G01X28801Y439278D01*
G37*
G36*
G01X28609Y399600D02*
G02X23989Y399601I-2310J1D01*
G01Y403376D01*
G02X28609I2310J0D01*
G01Y399600D01*
G37*
G36*
G01Y383853D02*
G02X23989Y383854I-2310J1D01*
G01Y387629D01*
G02X28609I2310J0D01*
G01Y383853D01*
G37*
G36*
G01X851323Y252284D02*
G02X851233Y247664I-45J-2310D01*
G01X847834Y247730D01*
G02X847923Y252350I44J2310D01*
G01X851323Y252284D01*
G37*
G36*
G01X120532Y248709D02*
X120497Y248888D01*
X120494D01*
X120092Y252425D01*
X120100Y252433D01*
X120093Y252524D01*
G02X124664Y253129I2304J163D01*
G01X124699Y252950D01*
X124702D01*
X125104Y249412D01*
X125102D01*
X125108Y249225D01*
G02X120532Y248709I-2309J-75D01*
G37*
G36*
G01X880388Y240102D02*
G02X875768Y240103I-2310J1D01*
G01Y243878D01*
G02X880388I2310J0D01*
G01Y240102D01*
G37*
G36*
G01X152309Y239728D02*
G02X147689Y239729I-2310J1D01*
G01Y243504D01*
G02X152309I2310J0D01*
G01Y239728D01*
G37*
G36*
G01X88902Y126569D02*
G02X84296Y126931I-2303J181D01*
G01X84596Y130747D01*
G02X89202Y130386I2303J-181D01*
G01X88902Y126569D01*
G37*
G36*
G01X29831Y1671683D02*
X29868Y1671670D01*
X31469Y1671768D01*
X31504Y1671784D01*
G02X31763Y1667523I990J-2078D01*
G01X31726Y1667536D01*
X30125Y1667438D01*
X30090Y1667422D01*
G02X29831Y1671683I-990J2078D01*
G37*
G36*
G01X29128Y1663280D02*
X29153Y1663274D01*
X31331Y1663330D01*
X31356Y1663337D01*
G02X31471Y1658886I643J-2210D01*
G01X31446Y1658892D01*
X29268Y1658836D01*
X29243Y1658829D01*
G02X29128Y1663280I-643J2210D01*
G37*
G36*
G01X30984Y1626606D02*
X28932Y1627819D01*
X28906Y1627826D01*
G02X31159Y1631645I593J2224D01*
G01X31178Y1631625D01*
X33232Y1630412D01*
X33259Y1630405D01*
G02X31003Y1626586I-596J-2224D01*
G01X30984Y1626606D01*
G37*
G36*
G01X31654Y1611314D02*
X29544D01*
X29518Y1611307D01*
G02Y1615741I-619J2217D01*
G01X29544Y1615734D01*
X31654D01*
X31680Y1615741D01*
G02Y1611307I619J-2217D01*
G01X31654Y1611314D01*
G37*
G36*
G01X30330Y1569755D02*
X27102Y1569903D01*
X27099D01*
G02X27310Y1574499I23J2302D01*
G01X27313D01*
X30540Y1574351D01*
X30543D01*
G02X30333Y1569755I-22J-2302D01*
G01X30330D01*
G37*
G36*
G01X29782Y1518465D02*
X29789Y1518491D01*
Y1520855D01*
X29782Y1520881D01*
G02X34216I2217J619D01*
G01X34209Y1520855D01*
Y1518491D01*
X34216Y1518465D01*
G02X29782I-2217J-619D01*
G37*
G36*
G01X33348Y1479670D02*
X31669Y1479847D01*
X31632Y1479837D01*
G02X32081Y1484082I-633J2213D01*
G01X32116Y1484063D01*
X33794Y1483886D01*
X33832Y1483896D01*
G02X33383Y1479651I633J-2213D01*
G01X33348Y1479670D01*
G37*
G36*
G01X126312Y1468141D02*
X126293Y1468106D01*
X126017Y1465700D01*
X126027Y1465663D01*
G02X121786Y1466151I-2219J-613D01*
G01X121805Y1466185D01*
X122081Y1468591D01*
X122071Y1468628D01*
G02X126312Y1468141I2219J613D01*
G37*
G36*
G01X29485Y1450459D02*
X29523Y1450445D01*
X31080Y1450515D01*
X31116Y1450532D01*
G02X31306Y1446285I978J-2084D01*
G01X31268Y1446299D01*
X29711Y1446229D01*
X29675Y1446212D01*
G02X29485Y1450459I-978J2084D01*
G37*
G36*
G01X29054Y1413851D02*
Y1413859D01*
X32505Y1413777D01*
X32512Y1413770D01*
X32587Y1413766D01*
G02X32396Y1409167I-136J-2298D01*
G01Y1409159D01*
X28944Y1409241D01*
Y1409242D01*
X28764Y1409260D01*
G02X29054Y1413851I236J2290D01*
G37*
G36*
G01X27808Y1371991D02*
Y1371987D01*
X27857Y1368569D01*
Y1368566D01*
G02X23257Y1368501I-2299J-120D01*
G01Y1368505D01*
X23208Y1371922D01*
Y1371926D01*
G02X27808Y1371991I2299J120D01*
G37*
G36*
G01X89190Y1346539D02*
Y1342952D01*
G02X84590I-2300J-92D01*
G01Y1346543D01*
G02X89190I2300J92D01*
G01Y1346539D01*
G37*
G36*
G01X52602Y699187D02*
Y699183D01*
X52706Y695966D01*
Y695962D01*
G02X48108Y695814I-2296J-161D01*
G01Y695818D01*
X48004Y699034D01*
Y699038D01*
G02X52602Y699187I2296J163D01*
G37*
G36*
G01X24435Y651912D02*
X24432Y652089D01*
X24431D01*
X24693Y656685D01*
X24720Y656872D01*
G02X29301Y656595I2279J-322D01*
G01X29304Y656418D01*
X29305D01*
X29043Y651826D01*
X29042D01*
X29019Y651652D01*
G02X24435Y651912I-2282J305D01*
G37*
G36*
G01X28868Y639508D02*
Y636042D01*
G02X24268I-2300J-92D01*
G01Y639512D01*
G02X28868I2300J92D01*
G01Y639508D01*
G37*
G36*
G01X29799Y623761D02*
Y620295D01*
G02X25199I-2300J-92D01*
G01Y623765D01*
G02X29799I2300J92D01*
G01Y623761D01*
G37*
G36*
G01X117986Y129129D02*
Y126894D01*
X118001Y126857D01*
G02X113751I-2125J-884D01*
G01X113766Y126894D01*
Y129129D01*
X113751Y129166D01*
G02X118001I2125J884D01*
G01X117986Y129129D01*
G37*
G54D28*
X78150Y28858D03*
Y178464D03*
Y434370D03*
Y583976D03*
Y839882D03*
Y989488D03*
Y1245394D03*
Y1395000D03*
Y1650906D03*
Y1800512D03*
X158071Y191614D03*
Y341220D03*
Y597126D03*
Y746732D03*
Y1002638D03*
Y1152244D03*
Y1408150D03*
Y1557756D03*
Y1813662D03*
Y1963268D03*
X886417Y191614D03*
Y341220D03*
Y597126D03*
Y746732D03*
Y1002638D03*
Y1152244D03*
Y1408150D03*
Y1557756D03*
Y1813662D03*
Y1963268D03*
G54D27*
X9843Y153168D03*
Y265767D03*
Y353144D03*
Y717711D03*
Y762617D03*
Y875216D03*
Y1137420D03*
Y1250019D03*
Y1337396D03*
Y1701963D03*
Y1746869D03*
Y1859468D03*
G54D24*
X45300Y1737100D03*
X97200Y513400D03*
G54D29*
X1019291Y1416024D03*
Y1694212D03*
G54D26*
X78749Y664550D03*
G54D25*
X32299Y1497550D03*
G54D16*
X68898Y17047D03*
Y190275D03*
Y422559D03*
Y595787D03*
Y828071D03*
Y1001299D03*
Y1233583D03*
Y1406811D03*
Y1639095D03*
Y1812323D03*
X167323Y179803D03*
Y353031D03*
Y585315D03*
Y758543D03*
Y990827D03*
Y1164055D03*
Y1396339D03*
Y1569567D03*
Y1801851D03*
Y1975079D03*
X895669Y179803D03*
Y353031D03*
Y585315D03*
Y758543D03*
Y990827D03*
Y1164055D03*
Y1396339D03*
Y1569567D03*
Y1801851D03*
Y1975079D03*
G54D14*
X8750Y1086250D03*
X8499Y1937550D03*
X5303Y1947050D03*
X11703Y1951946D03*
X93999Y58550D03*
X92900Y66128D03*
X89800Y132400D03*
X92999Y86128D03*
Y96128D03*
X74499Y84050D03*
Y80650D03*
X86899Y130567D03*
X86599Y126750D03*
X74999Y74050D03*
Y70550D03*
X78700Y70700D03*
Y74200D03*
X15750Y102250D03*
X41999Y200050D03*
X65999Y216050D03*
X95350Y204550D03*
X89800Y208550D03*
X24300Y247300D03*
X29699Y388484D03*
X29599Y382884D03*
X29999Y398684D03*
X23499Y397579D03*
X23399Y373931D03*
Y389679D03*
X23499Y381831D03*
X26299Y383854D03*
Y387629D03*
X28100Y374000D03*
X26492Y439350D03*
X26599Y442749D03*
X26299Y399601D03*
Y403376D03*
Y478404D03*
X26899Y454850D03*
X26515Y481798D03*
X45800Y405200D03*
X26799Y458497D03*
X26486Y462648D03*
X26499Y466250D03*
X64403Y471046D03*
X64397Y474446D03*
X26524Y426720D03*
X26399Y423322D03*
X29899Y404384D03*
X28900Y429200D03*
X29365Y421169D03*
X29500Y460800D03*
X28700Y451900D03*
X28800Y436700D03*
X28700Y445700D03*
X68000Y475600D03*
X67800Y469900D03*
X23499Y468447D03*
X23399Y476295D03*
Y444799D03*
X23499Y452699D03*
X23399Y460547D03*
Y429051D03*
X23499Y436951D03*
X23600Y405700D03*
X77499Y469550D03*
X61400Y452600D03*
X35900Y412600D03*
X65000Y455500D03*
X28900Y417800D03*
X39217Y554750D03*
X42867Y548450D03*
X43099Y555850D03*
X33699Y561850D03*
X46299Y552950D03*
X36499Y517775D03*
Y521550D03*
X26399Y501966D03*
Y505741D03*
X64600Y486300D03*
X64700Y489700D03*
X33307Y557938D03*
X26199Y547176D03*
X93200Y510500D03*
X83700Y529500D03*
X28600Y508500D03*
X35300Y524800D03*
X38400Y514900D03*
X88999Y538050D03*
X68900Y490600D03*
X68700Y485200D03*
X28600Y499300D03*
X26900Y532800D03*
X63499Y538550D03*
Y533050D03*
X22800Y539600D03*
X23499Y515691D03*
X23399Y523539D03*
X23499Y531439D03*
X23399Y492043D03*
X23499Y499943D03*
X23399Y507791D03*
X23499Y484195D03*
X77999Y493050D03*
X77499Y502550D03*
X29999Y557150D03*
X26599Y525648D03*
X95500Y513400D03*
X26599Y529302D03*
X60003Y534150D03*
X86199Y536025D03*
X59999Y537550D03*
X86199Y532250D03*
X65599Y514250D03*
X49799Y559150D03*
X68000Y546500D03*
X72500Y545000D03*
X27199Y539600D03*
X42202Y608195D03*
X39600Y626984D03*
X41400Y611500D03*
X42709Y625607D03*
X38300Y633800D03*
X41500Y642800D03*
X27499Y620203D03*
Y623857D03*
X36499Y566350D03*
X37999Y611550D03*
X42599Y567850D03*
X32800Y578200D03*
X47543Y578340D03*
X44959Y575756D03*
X30712Y624971D03*
X29999Y640550D03*
X60076Y595777D03*
X55499Y595650D03*
X29819Y634951D03*
X26869Y616861D03*
X23399Y641649D03*
X23499Y618053D03*
X23799Y625950D03*
X23499Y633801D03*
X23999Y609250D03*
X22978Y588571D03*
X22699Y577950D03*
X22999Y565550D03*
X57800Y634300D03*
X34976Y619250D03*
X44900Y642800D03*
X26568Y635950D03*
Y639604D03*
X47101Y632355D03*
X28000Y578500D03*
X25581Y567763D03*
X47626Y611300D03*
X45701Y607700D03*
X27699Y573750D03*
X82499Y627050D03*
X26800Y611500D03*
X41500Y635000D03*
X52500D03*
X48999Y642900D03*
X81251Y607249D03*
Y619251D03*
X28808Y593150D03*
X28700Y596549D03*
X32200Y603710D03*
X31598Y607102D03*
X80499Y664550D03*
X30999Y656250D03*
X29999Y694550D03*
X30999Y650550D03*
X81999Y668050D03*
X74499Y662050D03*
X25999Y694870D03*
X23999Y689050D03*
X23499Y665297D03*
X23699Y673150D03*
X23499Y681045D03*
Y649549D03*
X23725Y657471D03*
X78499Y654050D03*
X26737Y651957D03*
X26999Y656550D03*
X27687Y667447D03*
Y671101D03*
X76999Y664550D03*
X27700Y682700D03*
X50410Y695801D03*
X50300Y699200D03*
X44046Y799554D03*
X32800Y803050D03*
X46887Y803413D03*
X37416Y799033D03*
X37099Y811350D03*
X51100Y806300D03*
X49900Y813200D03*
X56281Y801350D03*
X27299Y783550D03*
X35300Y789375D03*
X90700Y792900D03*
X35559Y795112D03*
X45100Y793100D03*
X37216Y807951D03*
X76540Y850938D03*
X29299Y836901D03*
X75500Y847700D03*
X49300Y836500D03*
X46700Y820100D03*
X40400Y840792D03*
X89000Y816500D03*
X48346Y844529D03*
X58699Y837250D03*
X26299Y815050D03*
X92999Y868550D03*
X92499Y876550D03*
X68860Y838706D03*
X90000Y826000D03*
X54074Y815750D03*
X69499Y842950D03*
X62405Y820300D03*
X63499Y843050D03*
X90500Y831500D03*
X31699Y814350D03*
X65500Y817700D03*
X23299Y863050D03*
X26662Y861550D03*
X39649Y822000D03*
X80500Y817000D03*
X74220Y854150D03*
X72362Y849550D03*
X25000Y858100D03*
X46576Y832951D03*
X29600Y854000D03*
X24000Y853500D03*
X89400Y935400D03*
X89499Y942850D03*
X94999Y901550D03*
X85999Y940429D03*
X86399Y937050D03*
X29000Y896500D03*
X72000Y1013400D03*
X63273Y1023974D03*
X90000Y993100D03*
X92600Y996100D03*
X80699Y1004450D03*
Y1000450D03*
X20400Y1048300D03*
X66499Y1025050D03*
X75900Y1019100D03*
X63500Y1029600D03*
X88000Y1008500D03*
X75500Y1012261D03*
X80000Y1090500D03*
X80500Y1097550D03*
Y1104500D03*
X76999Y1196550D03*
X21817Y1156317D03*
X78499Y1273550D03*
X78613Y1282664D03*
X78779Y1302664D03*
X91279Y1340642D03*
X89999Y1348050D03*
X27499Y1387550D03*
X24499Y1389663D03*
X22851Y1374169D03*
X22999Y1366050D03*
X23700Y1354600D03*
X23499Y1381500D03*
X78779Y1312664D03*
X86165Y1339050D03*
X25507Y1372045D03*
X25558Y1368447D03*
X86890Y1346635D03*
Y1342860D03*
X28499Y1391050D03*
X32333Y1389383D03*
X20999Y1352050D03*
Y1320550D03*
X77758Y1357742D03*
X25000D03*
X30378Y1462518D03*
X33915Y1462681D03*
X32094Y1448448D03*
X28697Y1448296D03*
X33000Y1393000D03*
X33400Y1408100D03*
X36198Y1446749D03*
X26800Y1443800D03*
X30600Y1415100D03*
X30999Y1438050D03*
X27999Y1430050D03*
X29100Y1459200D03*
X34200Y1466200D03*
X23028Y1468579D03*
X23499Y1460550D03*
X22999Y1453050D03*
X23499Y1445050D03*
X22999Y1437050D03*
X23999Y1429050D03*
X23499Y1421550D03*
X23999Y1413550D03*
X32451Y1411468D03*
X28999Y1411550D03*
X33206Y1432352D03*
X30499Y1434550D03*
X30500Y1395500D03*
X76000Y1431100D03*
X34896Y1555730D03*
X34099Y1497550D03*
X30499D03*
X80043Y1544691D03*
X83932Y1544705D03*
X29631Y1533063D03*
X31999Y1517846D03*
Y1521500D03*
X46700Y1546793D03*
X34465Y1481683D03*
X30999Y1482050D03*
X44299Y1550950D03*
X96200Y1550100D03*
X32700Y1485200D03*
X28999Y1478050D03*
X27100Y1494300D03*
X34900Y1501000D03*
X35400Y1522200D03*
X35999Y1514550D03*
X29600Y1515300D03*
X24423Y1527123D03*
X22999Y1500050D03*
Y1515550D03*
X23799Y1508050D03*
X24499Y1492050D03*
X23599Y1476350D03*
X23277Y1484050D03*
X25247Y1546912D03*
X37999Y1530900D03*
X38500Y1534600D03*
X32099Y1535550D03*
X30115Y1511900D03*
X33512Y1512051D03*
X90324Y1538800D03*
X26705Y1534795D03*
X30199Y1545450D03*
X24199Y1523700D03*
X79000Y1555500D03*
X82429D03*
X36340Y1558809D03*
X78600Y1561900D03*
X29499Y1630050D03*
X75000Y1561800D03*
X28899Y1613524D03*
X42199Y1601050D03*
X38208Y1569841D03*
X25521Y1563350D03*
X30520Y1572049D03*
X32299Y1613524D03*
X34599Y1595300D03*
X24900Y1569500D03*
X31149Y1568300D03*
X26999Y1610550D03*
X34884Y1615734D03*
X32199Y1633124D03*
X34816Y1630953D03*
X22999Y1626050D03*
X23499Y1634050D03*
Y1618050D03*
X22699Y1594224D03*
X23499Y1610050D03*
Y1602050D03*
X23608Y1572653D03*
X24323Y1559950D03*
X31099Y1595350D03*
X32663Y1628181D03*
X27123Y1572205D03*
X33599Y1600200D03*
X74800Y1584700D03*
X74700Y1574600D03*
X39000Y1573500D03*
X89373Y1561073D03*
X85600Y1561500D03*
X80400Y1571766D03*
X82329Y1568117D03*
X31999Y1661127D03*
X28600Y1661039D03*
X29626Y1645002D03*
X33026Y1645051D03*
X95499Y1665418D03*
X33100Y1648500D03*
X47400Y1721700D03*
X34699Y1663300D03*
X27499Y1657050D03*
X26785Y1642089D03*
X22999Y1665550D03*
X92873Y1708176D03*
X24244Y1681868D03*
X22864Y1673550D03*
X23499Y1657050D03*
X23999Y1649550D03*
X23415Y1641634D03*
X92479Y1718176D03*
X78100Y1688189D03*
X92900Y1678176D03*
X93999Y1703050D03*
X74500Y1692000D03*
X21600Y1702900D03*
X32700Y1673300D03*
X32494Y1669706D03*
X29100Y1669500D03*
X30274Y1787238D03*
X85599Y1797350D03*
X38878Y1799571D03*
X47899Y1798650D03*
X36300Y1805123D03*
X35675Y1783450D03*
X39324Y1780623D03*
X39000Y1750800D03*
X43751Y1780559D03*
X42275Y1754000D03*
X48049Y1791450D03*
X40400Y1735600D03*
X47900Y1731300D03*
X47800Y1740500D03*
X89306Y1746856D03*
X89499Y1753575D03*
X85341Y1752245D03*
X85194Y1748848D03*
X46999Y1779550D03*
X37699Y1789850D03*
X46199Y1783050D03*
X74400Y1778100D03*
X38094Y1785840D03*
X41200Y1747050D03*
X42199Y1792250D03*
X37574Y1794050D03*
X45799Y1757650D03*
X46799Y1794900D03*
X47440Y1761391D03*
X31811Y1790271D03*
X47400Y1765250D03*
X43559Y1767884D03*
X40478Y1795820D03*
X32099Y1797150D03*
X47604Y1769005D03*
X45782Y1771877D03*
X47499Y1775350D03*
X45877Y1728477D03*
Y1724823D03*
X47000Y1737100D03*
X43600D03*
X28550Y1828153D03*
X29599Y1844350D03*
X29899Y1821050D03*
X34099Y1822850D03*
X60449Y1842550D03*
X80099Y1817250D03*
X28123Y1831527D03*
X35876Y1812350D03*
X34129Y1815267D03*
X86649Y1817100D03*
X61009Y1822340D03*
X36532Y1825352D03*
X36399Y1828750D03*
X26099Y1824950D03*
X25999Y1842550D03*
X46499Y1836550D03*
X47166Y1839884D03*
X80999Y1836550D03*
X90000Y1827900D03*
X43099Y1833850D03*
X39699D03*
X93500Y1827900D03*
X40500Y1863000D03*
X22367Y1836633D03*
X50299Y1946650D03*
X53999D03*
X42532Y1946783D03*
X44399Y1942250D03*
X38703Y1946754D03*
X34799Y1946750D03*
X46565Y1946703D03*
X44368Y1951450D03*
X45999Y1971450D03*
X28799Y1919060D03*
X14999Y1940050D03*
X15099Y1944050D03*
X50499Y1961550D03*
X14999Y1936050D03*
X17499Y1961050D03*
X43462Y1961160D03*
X32999Y1960555D03*
X23030Y1922038D03*
X25499Y1956050D03*
X42499Y1902550D03*
X48499Y1897050D03*
X26765Y1921945D03*
X57999Y1891050D03*
X31799Y1979050D03*
X112999Y124050D03*
X111790Y132259D03*
X152499Y149550D03*
X173499Y149050D03*
X175999Y82428D03*
X97499Y90050D03*
X115876Y125973D03*
Y130050D03*
X174999Y79050D03*
X175499Y86572D03*
X178999Y79050D03*
X176399Y94872D03*
X127999Y157050D03*
X114900Y177900D03*
X173500Y166315D03*
X154200Y168500D03*
X149400Y166400D03*
X149999Y243504D03*
Y239729D03*
X122397Y252688D03*
X122799Y249150D03*
X147099Y245350D03*
X124999Y246050D03*
X123300Y256000D03*
X157440Y283924D03*
Y303924D03*
Y313924D03*
X141499Y427550D03*
X166500Y428500D03*
X153459Y427494D03*
X154101Y445550D03*
X141499Y423050D03*
X159600Y446399D03*
X152000Y520813D03*
X171722Y513827D03*
X163549Y517100D03*
X140940Y561800D03*
X102100Y514900D03*
X163449Y521650D03*
X107526Y528996D03*
X104502Y530552D03*
X138999Y524213D03*
X173100Y483100D03*
X168453Y527949D03*
X160932Y549468D03*
X135499Y517550D03*
X107499Y497050D03*
X98900Y513400D03*
X172499Y491053D03*
X137899Y545451D03*
X176799Y493850D03*
X150750Y540416D03*
X109400Y543200D03*
X149000Y537500D03*
X106000Y543200D03*
X156500Y554000D03*
X138416Y553500D03*
X125499Y635550D03*
Y638950D03*
X127999Y645550D03*
X131400Y644600D03*
X144238Y645356D03*
X161000Y639100D03*
X124999Y643050D03*
X129000Y636600D03*
X128600Y640500D03*
X140900Y644000D03*
X134300Y646400D03*
X107000Y604800D03*
X105100Y600000D03*
X157000Y573851D03*
X141300Y565900D03*
X160824Y577000D03*
X144238Y649131D03*
X140400Y649800D03*
X158885Y679436D03*
Y689436D03*
X141500Y711000D03*
X158385Y719436D03*
X111200Y799450D03*
X110195Y809979D03*
X110500Y790200D03*
X110700Y795700D03*
X109831Y806598D03*
X109700Y803200D03*
X110202Y813379D03*
X154799Y838050D03*
X165499Y815550D03*
X110499Y834550D03*
X172660Y815731D03*
X174199Y841050D03*
X159500Y814700D03*
X169106Y815865D03*
X153900Y832200D03*
X98700Y842600D03*
Y822550D03*
X98000Y833500D03*
X163500Y937100D03*
X172500Y919294D03*
X108200Y963600D03*
X106749Y934367D03*
X108441Y924705D03*
X160399Y922850D03*
X153499Y918550D03*
X108845Y931657D03*
X109099Y928250D03*
X171100Y935000D03*
X102100Y968500D03*
X99000Y965000D03*
X172000Y961000D03*
X152500Y960000D03*
X170250Y948500D03*
X154749Y968249D03*
X171000Y939500D03*
X123999Y1054050D03*
Y1050650D03*
X120100Y1053200D03*
X124100Y1047100D03*
X112699Y1058974D03*
X104600Y980500D03*
X154749Y979149D03*
X103200Y985364D03*
X104700Y989900D03*
X120749Y1093990D03*
X164700Y1085400D03*
X105499Y1080550D03*
X106718Y1076050D03*
X105999Y1085800D03*
X101499Y1072550D03*
X125900Y1091282D03*
X132499Y1094550D03*
X137100Y1084800D03*
X140800Y1076300D03*
X121500Y1083600D03*
X121100Y1075300D03*
X116249Y1102550D03*
X112999Y1103740D03*
X117499Y1079300D03*
X157700Y1114948D03*
X157600Y1124948D03*
X159000Y1083000D03*
X127000Y1113500D03*
X123999Y1102550D03*
X138600Y1124600D03*
X116700Y1063500D03*
X105600Y1069500D03*
X108999Y1102050D03*
X137481Y1077557D03*
X137477Y1081177D03*
X124423Y1077523D03*
Y1081177D03*
X106999Y1194550D03*
X102900Y1196050D03*
X103686Y1223863D03*
X103999Y1216863D03*
X106162Y1205702D03*
X114999Y1210363D03*
X130699Y1210653D03*
X118999Y1219050D03*
X123970Y1221573D03*
X119399Y1298113D03*
X101541Y1262607D03*
X116999Y1288050D03*
X101399Y1292550D03*
X107999Y1307713D03*
X120507Y1317050D03*
X116499Y1328013D03*
X120507Y1328096D03*
X135850Y1322250D03*
X101500Y1352000D03*
X113500D03*
X113000Y1341000D03*
X102000D03*
X107228Y1330552D03*
X107500Y1340500D03*
X110499Y1365050D03*
X109999Y1355050D03*
X138000Y1359025D03*
X111499Y1311800D03*
X125999Y1315550D03*
X132999Y1319550D03*
X142667Y1319218D03*
X149562Y1315987D03*
X133475Y1331200D03*
X112440Y1358196D03*
X112999Y1361550D03*
X97229Y1373337D03*
X97000Y1377600D03*
X109228Y1337090D03*
Y1333315D03*
X102700Y1321363D03*
X119499Y1339050D03*
X121000Y1364000D03*
X148024Y1333525D03*
X140000Y1332600D03*
X129000Y1356500D03*
X113500Y1344500D03*
Y1348154D03*
X102350Y1344500D03*
Y1348154D03*
X147400Y1321600D03*
X125100Y1366000D03*
X124290Y1469241D03*
X123808Y1465050D03*
X117390Y1426201D03*
Y1429976D03*
X104935Y1440634D03*
X142999Y1456373D03*
X104999Y1444941D03*
X106999Y1454450D03*
X100699Y1471050D03*
X139815Y1454438D03*
X139235Y1460973D03*
X123999Y1473050D03*
X127898Y1462441D03*
X107300Y1438100D03*
X114499Y1432050D03*
X114000Y1425400D03*
X107999Y1448050D03*
X150338Y1453958D03*
X152499Y1462940D03*
X105099Y1459150D03*
X142900Y1460000D03*
X100800Y1536450D03*
X98599Y1491350D03*
X157440Y1490460D03*
Y1500460D03*
Y1520460D03*
Y1530460D03*
X100499Y1479650D03*
X122199Y1476050D03*
X99899Y1539850D03*
X100000Y1546650D03*
X97499Y1554550D03*
X96999Y1558050D03*
X98144Y1534309D03*
X157400Y1596550D03*
X160200Y1598500D03*
X150999Y1713550D03*
X171999Y1662250D03*
X131999Y1710050D03*
X117499Y1706050D03*
X128749Y1703300D03*
X169100Y1685800D03*
X133090Y1699959D03*
X109499Y1712213D03*
X104999Y1708963D03*
X141500Y1715500D03*
X117249Y1712090D03*
X165575Y1676975D03*
X112753Y1716613D03*
X152633Y1677967D03*
X122642Y1704243D03*
X112562Y1720613D03*
X135499Y1710150D03*
X118499Y1694050D03*
X123749Y1711550D03*
X177900Y1690400D03*
X169600Y1682300D03*
X109499Y1743550D03*
X107300Y1746300D03*
X107100Y1736000D03*
X109399Y1739550D03*
X99199Y1761899D03*
X99999Y1753575D03*
X141999Y1764550D03*
X110099Y1759875D03*
X101399Y1784700D03*
X165900Y1790500D03*
X161900Y1793400D03*
X123393Y1870859D03*
X137999Y1861497D03*
Y1865151D03*
X123592Y1874254D03*
X96600Y1826000D03*
X135999Y1881550D03*
X141300Y1866400D03*
X141800Y1860500D03*
X97999Y1843050D03*
X159421Y1925972D03*
X210638Y62959D03*
X210634Y66863D03*
X201499Y104550D03*
X245499Y100550D03*
X246499Y86050D03*
Y80550D03*
X215138Y72559D03*
X210685Y74725D03*
X210605Y70692D03*
X205938Y72528D03*
X210738Y78459D03*
Y82159D03*
X186999Y99050D03*
X213499Y104650D03*
X223499Y108150D03*
X188999Y120800D03*
X205499Y105550D03*
X225499Y68550D03*
X233749Y110800D03*
X230749Y76300D03*
X207999Y109550D03*
X237899Y107050D03*
X197899Y165075D03*
X218499Y190550D03*
X225298Y281114D03*
X213499Y283864D03*
X253871Y291410D03*
X250300Y275100D03*
X250400Y283100D03*
X239600Y278600D03*
X213400Y355300D03*
X224998Y357049D03*
X233998Y357549D03*
X239400Y357400D03*
X252935Y319114D03*
X214063Y318114D03*
X231800Y318414D03*
X179700Y425800D03*
X187699Y492850D03*
X199900Y554050D03*
X182499Y532550D03*
X220000Y516400D03*
X183499Y556100D03*
X188000Y484500D03*
X193549Y575875D03*
X216999Y686550D03*
X213999Y725050D03*
X230849Y726050D03*
X252499D03*
X254499Y697700D03*
X249700Y682500D03*
X249800Y689900D03*
X238500Y680800D03*
X228999Y765550D03*
X218224Y765325D03*
X241600Y765700D03*
X236800Y765800D03*
X199000Y815000D03*
X200539Y890300D03*
X211750Y894600D03*
X198924Y975975D03*
X229562Y904113D03*
X215499Y905550D03*
X200799Y896600D03*
X233500Y1066100D03*
X226800Y1093400D03*
X221800Y1069300D03*
X256000Y1133000D03*
X255000Y1125700D03*
X221300Y1083238D03*
X251500Y1136700D03*
X229800Y1073600D03*
X242000Y1066000D03*
X182500Y1275500D03*
X199149Y1362900D03*
X194700Y1385700D03*
X181000Y1365500D03*
X180500Y1369900D03*
X229025Y1471576D03*
X241000Y1469600D03*
X232650Y1493450D03*
X233700Y1481600D03*
X199500Y1627000D03*
X179999Y1655887D03*
X186000Y1644000D03*
X179999Y1644500D03*
X181100Y1682700D03*
X194049Y1792600D03*
X201499Y1781050D03*
X227814Y1887513D03*
X236225Y1883125D03*
X229800Y1875700D03*
X218100Y1886400D03*
X213138Y1952703D03*
X249499Y1928050D03*
X231999Y1914050D03*
X210999Y1942050D03*
X223436Y1890465D03*
X232314Y1890513D03*
X213562Y1926113D03*
X220062Y1931113D03*
X240964Y1934113D03*
X214999Y1909550D03*
X257499Y1911050D03*
X249600Y1896800D03*
X343499Y60150D03*
X296099Y17100D03*
X305099Y17000D03*
X311400Y17100D03*
X317000Y17300D03*
X341499Y63050D03*
Y67110D03*
X343499Y31650D03*
X308999Y87050D03*
X291999Y94050D03*
X282800Y87500D03*
X297499Y97550D03*
X315800Y100500D03*
X324800Y89400D03*
X293999Y293550D03*
X326499Y334054D03*
X284999Y338650D03*
X281499Y338550D03*
X313039Y352350D03*
X321900Y364600D03*
X298800Y333000D03*
X294500Y339000D03*
X326499Y337454D03*
X301249Y346050D03*
X344520Y406329D03*
X308999Y716450D03*
X315999Y718950D03*
X279939Y728610D03*
X329499Y801550D03*
X330540Y795509D03*
X327999Y740550D03*
X320499Y798050D03*
X285499Y745050D03*
X282099D03*
X292999Y743650D03*
X298000Y743500D03*
X323249Y749010D03*
X324959Y766750D03*
X277039Y740300D03*
X327749Y744050D03*
X306500Y753550D03*
X340699Y1046086D03*
X269500Y1135500D03*
X282500Y1135000D03*
X283499Y1556050D03*
X279999D03*
X289999Y1554650D03*
X293700Y1553351D03*
X276039Y1551300D03*
X314999Y1527550D03*
X326500Y1550200D03*
X261999Y1516050D03*
X295000Y1513000D03*
X297800Y1561600D03*
X291400Y1561500D03*
X324000Y1562500D03*
X312999Y1566050D03*
X323999Y1577250D03*
X330300Y1561200D03*
X310249Y1569800D03*
X264499Y1964050D03*
X331622Y1944767D03*
X288709Y1948042D03*
X284999Y1947691D03*
X342999Y1947409D03*
X342621Y1943409D03*
X280689Y1942710D03*
X315999Y1958550D03*
X327100Y1966472D03*
X329999Y1952273D03*
X325221Y1927272D03*
X313499Y1919050D03*
X332103Y1948133D03*
X310499Y1957050D03*
X285499Y1930050D03*
X381999Y57050D03*
X398799Y36152D03*
X381999Y50150D03*
X386799Y45000D03*
X381999Y53550D03*
X394199Y45050D03*
X358999Y61550D03*
X354999Y72050D03*
X426000Y93500D03*
X357503Y77043D03*
X374499Y77550D03*
X385999Y78050D03*
X401499Y80550D03*
X371700Y85500D03*
X400499Y406329D03*
X371999Y549300D03*
X394649Y630600D03*
X350499Y597300D03*
X375999Y698550D03*
X350499Y715050D03*
X371500Y880600D03*
X364499Y1099050D03*
X372999Y1123550D03*
X345499Y1096550D03*
X370149Y1320050D03*
X345424Y1310050D03*
X347324Y1524000D03*
X366149Y1554050D03*
X402499Y1476850D03*
X390999Y1514398D03*
Y1517798D03*
X349774Y1582900D03*
X354500Y1559500D03*
X400999Y1575550D03*
X354000Y1584900D03*
X353499Y1710450D03*
X377900Y1703800D03*
X348499Y1762050D03*
X385499Y1735050D03*
X367000Y1810000D03*
X360000Y1967500D03*
X645549Y1815134D03*
X644360Y1819137D03*
X659549Y1810634D03*
X757499Y745342D03*
Y1079550D03*
X755600Y1149800D03*
X758499Y1371050D03*
X757999Y1484050D03*
X754000Y1551000D03*
X732549Y1806634D03*
X733149Y1798634D03*
X690249Y1805634D03*
X707600Y1815600D03*
X733049Y1814134D03*
X755000Y1825000D03*
X711652Y1822109D03*
X711848Y1825504D03*
X758499Y1893550D03*
X752500Y1954500D03*
X821999Y193116D03*
X827499Y163550D03*
X820749Y163850D03*
X813249Y163800D03*
X839249Y164050D03*
X829917Y216200D03*
X833576Y215432D03*
X837999Y219550D03*
X822100Y279500D03*
X770999Y302050D03*
X785499Y291050D03*
X770999Y290050D03*
Y295550D03*
X827499Y313424D03*
X763571Y295622D03*
X777999Y296050D03*
X786978Y298529D03*
X836500Y274950D03*
X812500Y282750D03*
X809940Y264940D03*
X822100Y261700D03*
X816700Y274300D03*
X791499Y333050D03*
X789999Y336550D03*
X772499Y323050D03*
X758778Y345000D03*
X768178Y333964D03*
X784499Y334050D03*
X772873Y326924D03*
X780499Y330050D03*
X771105Y722789D03*
X835150Y677650D03*
X806500Y687250D03*
X781999Y725550D03*
X808660Y667540D03*
X820600Y664300D03*
X813200Y675900D03*
X788999Y736050D03*
X791999Y733050D03*
X766499Y732842D03*
X762500Y734000D03*
X784939Y733550D03*
X769999Y733050D03*
X792154Y1135926D03*
X771999Y1124550D03*
X767083Y1134550D03*
X764549Y1138500D03*
X784439Y1136550D03*
X814000Y1087000D03*
X772499Y1130050D03*
X789499Y1138050D03*
X779499Y1131050D03*
X807000Y1072900D03*
X825800Y1072300D03*
X815400Y1078800D03*
X803199Y1151850D03*
X822100Y1466800D03*
X774542Y1530050D03*
X804899Y1556950D03*
X836625Y1487400D03*
X771225Y1539474D03*
X767936Y1540336D03*
X784577Y1535628D03*
X812550Y1494050D03*
X774577Y1533796D03*
X791499Y1543550D03*
X793999Y1541050D03*
X784499Y1529050D03*
X809960Y1478040D03*
X814700Y1486300D03*
X788000Y1788000D03*
X774500D03*
X812000Y1799500D03*
X821249Y1791250D03*
X811000Y1793000D03*
X793000Y1803500D03*
X795849Y1805500D03*
X770999Y1820550D03*
X822499Y1815164D03*
X791999Y1819050D03*
X783499Y1827050D03*
X807000Y1822300D03*
X803500Y1822708D03*
X810900Y1882440D03*
X822700Y1871100D03*
X805900Y1887560D03*
X771499Y1936550D03*
X802499Y1951550D03*
X800431Y1941193D03*
X767999Y1945173D03*
X764908Y1946592D03*
X785939Y1946800D03*
X812500Y1898500D03*
X771499Y1940050D03*
X802099Y1961950D03*
X834799Y1946950D03*
X792499Y1949050D03*
X794499Y1941050D03*
X782999Y1937050D03*
X919800Y54600D03*
X924200Y69800D03*
X898800Y96000D03*
X855500Y149500D03*
X873000Y148500D03*
X846500Y149500D03*
X841499Y135550D03*
X861999Y146550D03*
X882499Y147050D03*
X896999Y141550D03*
X916499Y115050D03*
X923761Y85550D03*
X907499Y131800D03*
X902499Y110550D03*
X901499Y92050D03*
X898999Y110550D03*
X897555Y90494D03*
X910999Y124550D03*
X916499Y172550D03*
X867500Y163924D03*
X867576Y159924D03*
X878078Y240103D03*
Y243878D03*
X854400Y264600D03*
X847878Y250040D03*
X851278Y249974D03*
X842499Y280924D03*
X847500Y246600D03*
X850999Y246550D03*
X874700Y244900D03*
X874900Y238600D03*
X871999Y283924D03*
X886200Y313924D03*
X886600Y303924D03*
X872136Y273924D03*
X858478Y274050D03*
X868799Y294750D03*
X865499Y288050D03*
X867899Y321550D03*
X868299Y336150D03*
X902999Y556050D03*
X878596Y645573D03*
X875100Y644400D03*
X922049Y574375D03*
X879750Y570550D03*
X879950Y565050D03*
X851172Y655432D03*
X878596Y649348D03*
X847772Y655370D03*
X875300Y650500D03*
X851300Y651700D03*
X847600Y651600D03*
X852696Y671197D03*
X922049Y978575D03*
X900499Y962100D03*
X879708Y971892D03*
X878233Y1051095D03*
X877964Y1054485D03*
X850833Y1061441D03*
X847233Y1061492D03*
X847500Y1057800D03*
X851000Y1058000D03*
X874733Y1055792D03*
X874999Y1049550D03*
X900999Y979050D03*
X883083Y979183D03*
X864499Y1128750D03*
X852333Y1077716D03*
X871499Y1124948D03*
X872086Y1114948D03*
X871999Y1094948D03*
X872086Y1084948D03*
X860133Y1084142D03*
X860799Y1358925D03*
X861849Y1376050D03*
X866700Y1379796D03*
X866596Y1375796D03*
X848888Y1466402D03*
X852288Y1466346D03*
X878054Y1456450D03*
X877853Y1459991D03*
X874100Y1461600D03*
X874900Y1454000D03*
X848861Y1462463D03*
X852500Y1462600D03*
X867523Y1542821D03*
X867199Y1535150D03*
X854327Y1477550D03*
X858827Y1485696D03*
X872086Y1490460D03*
X871999Y1500460D03*
Y1520460D03*
X872086Y1530460D03*
X863699Y1501250D03*
X900500Y1721500D03*
X886439Y1717600D03*
X862800Y1712700D03*
X889800Y1711500D03*
X921549Y1788475D03*
X917499Y1796550D03*
X879700Y1786300D03*
X873300Y1740100D03*
X879664Y1782213D03*
X866914Y1861840D03*
X853499Y1871036D03*
X866914Y1865615D03*
X850099Y1871056D03*
X851500Y1821400D03*
X849375Y1824982D03*
X854905Y1825583D03*
X854480Y1867578D03*
X849999Y1867550D03*
X863700Y1867300D03*
X865300Y1858700D03*
X854814Y1883550D03*
X859314Y1891365D03*
X871921Y1905972D03*
X871421Y1895972D03*
X872086Y1925972D03*
Y1935972D03*
X863699Y1906450D03*
X857099Y1917650D03*
X961499Y100050D03*
X946899Y122550D03*
X932961Y85581D03*
X928461Y75981D03*
X928561Y91481D03*
X928508Y87747D03*
X928428Y83714D03*
X928561Y95181D03*
X928457Y79885D03*
X958999Y96050D03*
X930999Y115550D03*
X937999Y122050D03*
X938499Y115550D03*
X961499Y93350D03*
X926999Y122050D03*
X943499Y82550D03*
X934499Y118750D03*
X926999Y115050D03*
X939549Y175175D03*
X966499Y552050D03*
X965999Y954550D03*
X986400Y1639302D03*
X987100Y1624900D03*
X981200Y1625800D03*
X990425Y1633898D03*
X987029Y1634075D03*
X981200Y1618002D03*
X964000Y1639200D03*
X960900Y1636400D03*
X969600Y1638300D03*
X977500Y1660500D03*
X978000Y1668000D03*
X967600Y1651100D03*
X989502Y1646000D03*
X988800Y1658300D03*
X989000Y1663802D03*
X987200Y1675600D03*
X989900Y1678800D03*
X974000Y1670700D03*
X984211Y1667500D03*
X971558Y1646500D03*
X981500Y1653000D03*
X980800Y1659600D03*
X982050Y1649302D03*
G54D11*
X11999Y53550D03*
X11499Y34050D03*
X10000Y16500D03*
X11499Y142050D03*
X11999Y69050D03*
X6891Y161611D03*
X11302Y161500D03*
X7089Y166111D03*
X11500Y166000D03*
X9499Y301050D03*
Y281550D03*
X8999Y318550D03*
X8599Y751650D03*
X10999Y774050D03*
X8999Y889550D03*
X8499Y979050D03*
X8999Y961550D03*
Y942050D03*
Y926550D03*
X8499Y907050D03*
X8999Y1060550D03*
Y1041050D03*
Y1025550D03*
X8499Y1006050D03*
X8999Y988550D03*
X8499Y1078050D03*
X6500Y1146000D03*
X13000Y1145500D03*
Y1151000D03*
X7000Y1151500D03*
X8799Y1302550D03*
X7499Y1282050D03*
X7999Y1264550D03*
X9399Y1347350D03*
X8299Y1320050D03*
X7099Y1717750D03*
X7199Y1731450D03*
X6099Y1753750D03*
X11299Y1850050D03*
X9099Y1881550D03*
X8499Y1979550D03*
X11500Y1987000D03*
X92999Y52050D03*
X90899Y14850D03*
X23499Y27050D03*
X50999Y21150D03*
Y47750D03*
X27799Y38450D03*
X25799Y64050D03*
X65499Y59050D03*
Y41550D03*
Y27050D03*
X40999Y42050D03*
Y27550D03*
X17600Y5604D03*
X36000D03*
X55700Y5900D03*
X73900Y6200D03*
X90900Y5800D03*
X88000Y36400D03*
X93000Y44900D03*
X92900Y39700D03*
X52499Y145050D03*
Y130550D03*
X59499Y108050D03*
Y90550D03*
Y76050D03*
X96184Y151065D03*
X71015Y123666D03*
X78165Y137116D03*
X95814Y136065D03*
X77165Y110799D03*
X15302Y161500D03*
X19500D03*
X15500Y166000D03*
X19198Y152000D03*
X19698Y166000D03*
X92899Y231450D03*
X48499Y228550D03*
X23999Y229050D03*
X52499Y162550D03*
X96184Y166065D03*
X23895Y238995D03*
X51099Y300050D03*
X90899Y309550D03*
X93199Y279650D03*
X84899Y289250D03*
X86899Y242750D03*
X75299Y261750D03*
X42999Y275650D03*
X48499Y260550D03*
Y243050D03*
X23999Y261050D03*
Y243550D03*
X52199Y342350D03*
X89899Y368350D03*
X94199Y325550D03*
X93499Y337450D03*
X95499Y355450D03*
X89999Y396450D03*
X39999Y359550D03*
Y342050D03*
Y327550D03*
X15499Y360050D03*
Y342550D03*
Y328050D03*
X94500Y456800D03*
X75300Y454100D03*
X67300Y450200D03*
X68899Y445450D03*
X87599Y403950D03*
X76099Y414250D03*
X95399Y416350D03*
X89099Y426150D03*
X93499Y481550D03*
Y477050D03*
X93199Y449850D03*
X93500Y445300D03*
X42299Y564150D03*
X62055Y561550D03*
X49555Y563550D03*
X75999Y556640D03*
X70800Y540300D03*
X77165Y514650D03*
X94499Y486550D03*
X52333Y641295D03*
X72599Y578236D03*
X39999Y576550D03*
X61099Y603236D03*
X93599Y581236D03*
X92599Y606236D03*
X93100Y571640D03*
X47800Y692800D03*
X53210Y701486D03*
X43499Y657550D03*
X39899Y754850D03*
X39399Y768750D03*
X27199Y764950D03*
X28599Y775450D03*
X26399Y750850D03*
X14799Y751450D03*
X17299Y773950D03*
X79900Y791300D03*
X67999Y790400D03*
X53999Y791000D03*
X93299Y862050D03*
X26799Y874550D03*
X26099Y891650D03*
X76399Y820450D03*
X70100Y818900D03*
X93690Y887139D03*
X93900Y882400D03*
X94001Y856895D03*
X93808Y852063D03*
X93499Y892050D03*
X25699Y916150D03*
X25099Y942150D03*
X23899Y957950D03*
X93499Y897152D03*
X93000Y907165D03*
X77499Y921550D03*
X77002Y952079D03*
X76711Y948089D03*
X77499Y962152D03*
X83988Y934028D03*
X24799Y992250D03*
X33899Y1005950D03*
X65799Y994050D03*
X72799Y982950D03*
X86900Y981600D03*
X67000Y1011500D03*
X21500Y1122500D03*
Y1092500D03*
X17500D03*
X18000Y1145500D03*
X17500Y1150500D03*
X22447Y1223247D03*
X23200Y1209300D03*
X21299Y1300250D03*
X21799Y1282750D03*
X22321Y1231121D03*
X18099Y1343550D03*
X96000Y1369000D03*
X96100Y1384650D03*
X77166Y1353400D03*
X93316Y1351000D03*
X77165Y1327335D03*
X76499Y1507050D03*
Y1498050D03*
Y1512050D03*
Y1503050D03*
X76999Y1528050D03*
Y1519050D03*
X90999Y1628550D03*
Y1624550D03*
X91121Y1632549D03*
X86299Y1632550D03*
X85999Y1628550D03*
Y1624550D03*
X15299Y1723450D03*
X15399Y1708350D03*
X14899Y1736250D03*
X15299Y1753250D03*
X84099Y1737150D03*
X83599Y1744750D03*
X77165Y1759550D03*
X93499D03*
X94336Y1773113D03*
X78529Y1788113D03*
X38600Y1880200D03*
X31400Y1885200D03*
X30400Y1849650D03*
X23999Y1857950D03*
X27199Y1874350D03*
X52999Y1871550D03*
X57499Y1871050D03*
X82999Y1887550D03*
X78999D03*
X36100Y1892200D03*
X58999Y1958050D03*
X82499Y1957050D03*
X73499D03*
X66499D03*
X92499Y1959050D03*
X47499Y1915050D03*
X62999Y1914550D03*
Y1926050D03*
X81499Y1915550D03*
X47499Y1930550D03*
X62499Y1939550D03*
X73499Y1945550D03*
X83999Y1945050D03*
X78999Y1891550D03*
X82999D03*
X78999Y1896050D03*
X78433Y1900010D03*
X78999Y1904050D03*
X83499Y1896050D03*
X83433Y1904010D03*
X83999Y1900050D03*
X79500Y1987500D03*
X61500D03*
X44500Y1987000D03*
X26500D03*
X55999Y1982550D03*
X96999Y49550D03*
X157299Y5150D03*
X107000Y6000D03*
X97800Y36000D03*
X96900Y40400D03*
X167499Y43550D03*
X116400Y56000D03*
X129100Y55900D03*
X127499Y65050D03*
X141999Y65550D03*
X156499Y66050D03*
X169300Y130300D03*
X178700Y129900D03*
X152999Y141050D03*
X123499Y149050D03*
X133999D03*
X142999Y141050D03*
X132999Y141550D03*
X176499Y140050D03*
X167499Y149550D03*
X144499Y149050D03*
X163499Y140050D03*
X160999Y149550D03*
X123499Y140050D03*
X129999Y78050D03*
X166999Y88050D03*
X166499Y83550D03*
Y79050D03*
X158499D03*
Y84050D03*
Y88550D03*
Y93550D03*
X166999Y92550D03*
Y97050D03*
X127999Y99550D03*
X165499Y106050D03*
X169999Y103050D03*
X114800Y68500D03*
X177899Y199250D03*
X117500Y162300D03*
X124300Y167800D03*
X131799Y201950D03*
X142688Y218861D03*
X143110Y203861D03*
X97999Y199050D03*
X155999Y181050D03*
X135399Y277050D03*
X130799Y300250D03*
X158999Y259800D03*
X152808Y246341D03*
X166800Y240800D03*
X133000Y240500D03*
X157740Y273924D03*
X139399Y372350D03*
X167299Y369350D03*
X130099Y326150D03*
X134699Y356050D03*
X126099Y396150D03*
X152499Y395950D03*
X137100Y436800D03*
X129400Y426900D03*
X135999Y472550D03*
X135140Y478930D03*
X100500Y456700D03*
X99399Y437450D03*
X124899Y409050D03*
X133499Y445050D03*
X128999Y445550D03*
X130000Y452000D03*
X97699Y477050D03*
Y481550D03*
X149700Y471600D03*
X154100Y476500D03*
X164600Y476700D03*
X171300D03*
X97999Y445550D03*
X97699Y449850D03*
X147300Y526700D03*
X147590Y521500D03*
X108599Y557236D03*
X154099Y529236D03*
X101500Y536500D03*
X139200Y484300D03*
X134499Y488050D03*
X145649Y509550D03*
X136349Y509050D03*
X98999Y488050D03*
X140499Y499050D03*
X153499Y502550D03*
X148999D03*
X136299Y499050D03*
X108900Y587600D03*
X162500Y623400D03*
X140000Y587700D03*
X140499Y600550D03*
X152400Y643300D03*
X140499Y626050D03*
X143999Y605550D03*
X170799Y689150D03*
X171999Y672450D03*
X131099Y700450D03*
X139099Y707150D03*
X152124Y651868D03*
X159054Y665400D03*
X152499Y810550D03*
X110800Y772700D03*
X178899Y765250D03*
X172599Y774250D03*
X161999Y768050D03*
X152499Y816050D03*
Y820550D03*
Y825050D03*
X156499Y876050D03*
Y870550D03*
X97499Y862050D03*
X111299Y821050D03*
X172099Y877450D03*
X168499Y846713D03*
X173899Y846550D03*
X161999Y843550D03*
Y848050D03*
X156499Y846050D03*
X156999Y850050D03*
X158114Y883290D03*
X156499Y886950D03*
X155499Y891050D03*
Y896050D03*
X97700Y887400D03*
X97900Y882400D03*
X163999Y863050D03*
X159999D03*
X155999Y859050D03*
Y863050D03*
X97800Y851800D03*
X98001Y856950D03*
X97499Y892550D03*
X151999Y936550D03*
X152499Y931550D03*
X109500Y901100D03*
X153299Y943750D03*
X106500Y943000D03*
X105300Y960300D03*
X169299Y956350D03*
X159459Y896616D03*
X163499Y896550D03*
X157499Y909050D03*
Y904550D03*
X159186Y946117D03*
X151300Y1049300D03*
X171499Y998650D03*
X156499Y985950D03*
X149499Y997650D03*
X162499Y1023550D03*
X163499Y1035050D03*
X158300Y1015000D03*
X141234Y1029885D03*
X140864Y1044885D03*
X159499Y1044579D03*
X165600Y1057428D03*
X100999Y1099550D03*
X105000Y1100500D03*
X100999Y1095050D03*
X105006Y1095366D03*
X137900Y1103400D03*
X139100Y1097100D03*
X169299Y1067150D03*
X168099Y1083550D03*
X167999Y1092850D03*
X143200Y1116300D03*
X134500Y1108100D03*
X171599Y1139950D03*
X167499Y1118550D03*
X167999Y1130550D03*
X133200Y1132100D03*
X164999Y1075550D03*
X159055Y1070400D03*
X106999Y1114960D03*
X145900Y1163200D03*
X163499Y1171650D03*
X151699Y1158550D03*
X144399Y1171150D03*
X150999Y1181150D03*
X141499Y1185550D03*
X151499Y1173050D03*
X121657Y1224604D03*
X120999Y1188050D03*
X111999D03*
X102999D03*
X128400Y1188600D03*
X104999Y1231050D03*
X100999Y1231032D03*
X120999Y1228550D03*
X120499Y1264550D03*
X126499D03*
X123938Y1267623D03*
X103499Y1305050D03*
X117149Y1267550D03*
X175823Y1297070D03*
X175499Y1302113D03*
Y1306113D03*
Y1292550D03*
X145999Y1353050D03*
X167499Y1389050D03*
X123500Y1360300D03*
X156999Y1397750D03*
X143199Y1412050D03*
X163499Y1433350D03*
X166799Y1409350D03*
X178200Y1393400D03*
X176599Y1447450D03*
X172299Y1465850D03*
X165499Y1453550D03*
X157915Y1420460D03*
X140799Y1435460D03*
X166799Y1487450D03*
X176299Y1500150D03*
X159054Y1476200D03*
X124999Y1616050D03*
Y1620050D03*
Y1629050D03*
Y1633050D03*
X119999Y1629050D03*
X120100Y1633100D03*
X105749Y1712749D03*
X122499Y1668550D03*
Y1672550D03*
X126562Y1670613D03*
X118999Y1670550D03*
X172499Y1714050D03*
X167499Y1714113D03*
X162499D03*
X130499Y1730050D03*
X128000Y1735000D03*
X144499Y1729550D03*
X139500Y1730500D03*
X133000Y1734500D03*
X157500Y1797400D03*
X126599Y1789650D03*
X120299Y1796150D03*
X142144Y1801644D03*
X104417Y1791480D03*
X144499Y1745550D03*
X137999Y1747723D03*
X129999Y1747050D03*
X123499D03*
X117499Y1745050D03*
X170499Y1731050D03*
X165499Y1730613D03*
X172499Y1726613D03*
X167999D03*
X163499D03*
X97999Y1815050D03*
X104500Y1813400D03*
X173899Y1813250D03*
X177599Y1866750D03*
X168299Y1879850D03*
X168499Y1855550D03*
X127499Y1889050D03*
X126999Y1882550D03*
X111499Y1877550D03*
Y1882550D03*
X122999Y1883050D03*
X115999Y1882550D03*
X157999Y1840972D03*
X158000Y1825400D03*
X159054Y1881800D03*
X167200Y1868000D03*
X159054Y1855050D03*
X143491Y1856400D03*
X116499Y1877550D03*
X122999Y1889050D03*
X168899Y1960750D03*
X163599Y1892050D03*
X159173Y1935972D03*
X142499Y1905972D03*
X141499Y1895972D03*
X131100Y1908500D03*
X129600Y1912400D03*
X124433Y1908510D03*
X124999Y1912550D03*
X98433Y1940510D03*
X98999Y1944550D03*
X102433Y1940555D03*
X103433Y1944510D03*
X98000Y1987500D03*
X163500D03*
X146000D03*
X128500D03*
X115000Y1987000D03*
X246200Y65800D03*
X246000Y61300D03*
Y56500D03*
Y52100D03*
X245600Y43800D03*
X245500Y39100D03*
X247100Y47900D03*
X189499Y4550D03*
X206999Y5050D03*
X226499D03*
X241999D03*
X261499Y4550D03*
X225499Y52550D03*
Y46550D03*
Y63550D03*
Y58050D03*
X183499Y45550D03*
X192499Y57550D03*
X246000Y70800D03*
X244900Y149100D03*
X244499Y136550D03*
Y122050D03*
X229099Y161350D03*
X206899Y171650D03*
X190199Y178650D03*
X232400Y220700D03*
X210999Y221550D03*
X191999D03*
X227499Y192050D03*
X231999D03*
X227999Y187050D03*
X231999D03*
X227999Y182550D03*
X231999D03*
X227999Y178050D03*
X231999D03*
X249800Y248800D03*
X235399Y263350D03*
X201199Y266750D03*
X181299Y267350D03*
X217999Y250550D03*
X203499D03*
X185999D03*
X187199Y359050D03*
X223799Y365350D03*
X209199Y365050D03*
X181599Y396250D03*
X217599Y396450D03*
X258999Y396650D03*
X209999Y426150D03*
X237699Y426050D03*
X218499Y474850D03*
X251499Y446050D03*
X231999Y445550D03*
X251999Y462050D03*
X232499Y461550D03*
X209499Y412550D03*
X220000Y421000D03*
X232999Y414550D03*
X252499Y415050D03*
X194999Y490050D03*
X190499Y487550D03*
X191199Y491550D03*
X244199Y483350D03*
X224299Y494650D03*
X242099Y511750D03*
X244999Y559550D03*
Y545050D03*
X220499Y560050D03*
Y545550D03*
X257499Y530050D03*
Y512550D03*
Y498050D03*
X205300Y508100D03*
X190499Y507513D03*
X187499Y531613D03*
Y536113D03*
X193499Y541113D03*
X188999D03*
X193499Y549613D03*
X188999D03*
Y545613D03*
X193999Y545550D03*
X257199Y640050D03*
X224999Y613450D03*
X256499Y609050D03*
Y591550D03*
Y577050D03*
X245000Y647000D03*
X244499Y632050D03*
X219999Y647050D03*
Y632550D03*
X207300Y639400D03*
X206499Y623550D03*
Y609050D03*
X181999Y641550D03*
Y624050D03*
Y609550D03*
X244999Y577050D03*
X220499Y577550D03*
X199199Y659150D03*
X234200Y668300D03*
X226399Y677550D03*
X212999Y677350D03*
X190399Y689050D03*
X182599Y688350D03*
X246500Y663300D03*
X218800Y668700D03*
X224099Y770250D03*
X209500Y759000D03*
X208799Y766750D03*
X214799Y774750D03*
X245599Y773450D03*
X234299Y773750D03*
X247099Y795050D03*
X227199D03*
X197099D03*
X254699Y807650D03*
X233799Y806350D03*
X208299Y805350D03*
X198199Y805950D03*
X190699Y778350D03*
X215999Y887550D03*
X220499D03*
X215499Y883550D03*
X244099Y857450D03*
X245199Y878050D03*
X232399Y886550D03*
X252899Y886350D03*
X252399Y838250D03*
X245399Y823550D03*
X217300Y816800D03*
X198499Y884113D03*
X245399Y907450D03*
X243899Y923650D03*
X242199Y938750D03*
X256199Y916250D03*
X254899Y929250D03*
X253499Y938050D03*
X252499Y948850D03*
X244199Y973250D03*
X225299Y957650D03*
X213999Y958650D03*
X206699Y953050D03*
X203999Y943350D03*
X204699Y929450D03*
X205999Y978250D03*
X256499Y967050D03*
X233499Y966050D03*
X216999Y967550D03*
X219499Y939613D03*
Y948613D03*
Y943813D03*
X214999Y939613D03*
Y944113D03*
Y948613D03*
X219499Y926613D03*
X214999D03*
X254499Y984550D03*
X245899Y995250D03*
X232299Y981950D03*
X206299Y990250D03*
X207299Y1008150D03*
X202100Y1028100D03*
X253999Y1052050D03*
X253499Y1038550D03*
X232499Y1038050D03*
X216499Y1053050D03*
X215999Y1039550D03*
X258999Y1011550D03*
X233999Y1012550D03*
Y997050D03*
X217999Y1012050D03*
X217499Y998550D03*
Y981050D03*
X199499Y1093850D03*
X209900Y1093600D03*
X249499Y1104150D03*
X260349Y1139200D03*
X214499Y1154250D03*
X223099Y1182750D03*
X210199Y1173450D03*
X204199Y1163850D03*
X208199Y1145850D03*
X180400Y1202800D03*
X201600Y1205900D03*
X220999Y1224350D03*
X242199Y1210050D03*
X242599Y1198350D03*
X232599Y1195750D03*
X247899Y1208650D03*
X251999Y1184550D03*
X212499Y1212550D03*
X181700Y1219900D03*
X212499Y1184550D03*
X196499Y1224550D03*
Y1215550D03*
Y1196550D03*
X259999Y1152992D03*
X259499Y1161550D03*
X202199Y1276850D03*
X202899Y1291450D03*
X179500Y1262000D03*
X179800Y1244100D03*
X196399Y1236650D03*
X221599Y1237250D03*
X222299Y1251850D03*
X229899Y1250550D03*
X216300Y1274800D03*
X234299Y1232650D03*
X261199Y1227950D03*
X250900Y1248500D03*
X242900Y1263000D03*
X232799Y1276150D03*
X254899Y1289950D03*
X241399Y1303250D03*
X211499Y1267050D03*
Y1258050D03*
Y1239050D03*
X195499Y1279050D03*
Y1270050D03*
Y1251050D03*
X179999Y1306050D03*
Y1301550D03*
Y1292550D03*
Y1296613D03*
X239099Y1314150D03*
X252399Y1326350D03*
X219099Y1325950D03*
X226599Y1340250D03*
X207699Y1337950D03*
X195500Y1352500D03*
X213199Y1350050D03*
X227399Y1363050D03*
X234300Y1375700D03*
X217499Y1387450D03*
X249800Y1388400D03*
X245999Y1358050D03*
X246499Y1370050D03*
X245999Y1339050D03*
X208049Y1385550D03*
X258999Y1396950D03*
X230599Y1400250D03*
X217999Y1408850D03*
X204699Y1418350D03*
X203199Y1393250D03*
X201000Y1408500D03*
X180599Y1424050D03*
X180000Y1439500D03*
X204999Y1472650D03*
X250199Y1473550D03*
X226300Y1447800D03*
X230899Y1437350D03*
X238899Y1453750D03*
X259299Y1438750D03*
X227999Y1421550D03*
X212400Y1433700D03*
X194200Y1457900D03*
X244999Y1412550D03*
X245499Y1424550D03*
X181500Y1479000D03*
X202399Y1500750D03*
X208999Y1491250D03*
X247500Y1499000D03*
X248000Y1482000D03*
X212899Y1535550D03*
X230999D03*
X213399Y1500300D03*
X236999Y1535550D03*
X260999Y1503550D03*
X246200Y1617600D03*
X239400Y1624300D03*
X218000Y1614300D03*
X209200Y1624000D03*
X228999Y1637550D03*
X211999Y1568550D03*
X238300Y1575100D03*
X231499Y1575050D03*
X224499D03*
X217999Y1574550D03*
X211999D03*
X258700Y1645100D03*
X237400Y1663800D03*
X230600Y1670500D03*
X197600Y1694900D03*
X204400Y1688200D03*
X216601Y1684350D03*
X226800Y1684200D03*
X220100Y1691700D03*
X209901Y1691850D03*
X212000Y1701300D03*
X201801Y1701450D03*
X195001Y1708150D03*
X205200Y1708000D03*
X180701Y1716050D03*
X195500Y1717000D03*
X200600Y1663600D03*
X199900Y1670600D03*
X213000Y1672500D03*
X181900Y1675300D03*
X255699Y1722550D03*
X222700Y1710100D03*
X242999Y1658050D03*
X193499Y1674050D03*
X253999Y1676550D03*
X235499Y1697050D03*
X256499Y1710050D03*
X180000Y1731000D03*
X179701Y1724550D03*
X195000Y1725500D03*
X249199Y1743150D03*
X222499Y1743850D03*
X259499Y1760650D03*
X221499Y1760950D03*
X199699Y1761450D03*
X220799Y1791550D03*
X252199Y1793050D03*
X238699Y1801850D03*
X205199Y1801950D03*
X182299Y1801350D03*
X206900Y1726700D03*
X185999Y1746050D03*
X237999Y1730550D03*
X244999Y1755050D03*
X253899Y1813250D03*
X215299Y1813950D03*
X255999Y1855950D03*
X204399Y1855450D03*
X206999Y1867550D03*
X241199Y1867150D03*
X244700Y1878700D03*
X224800Y1867000D03*
X212399Y1885850D03*
X199599Y1879850D03*
X181099Y1885850D03*
X261499Y1825050D03*
X209999D03*
X192100Y1813500D03*
X228999Y1856050D03*
X226999Y1941050D03*
X241255Y1896055D03*
X205499Y1968650D03*
X183999Y1968150D03*
X190399Y1961250D03*
X207199Y1892850D03*
X191599Y1891550D03*
X238999Y1970550D03*
X232999Y1971050D03*
X227499D03*
X221300Y1971200D03*
X240900Y1979000D03*
X225199Y1978750D03*
X209699D03*
X188199Y1978250D03*
X254500Y1987500D03*
X236500D03*
X216999Y1987550D03*
X199000Y1987500D03*
X183000D03*
X199600Y1974900D03*
X289499Y39050D03*
X286603Y34928D03*
X278999Y5050D03*
X292999Y4550D03*
X310499Y5050D03*
X329999D03*
X306999Y55450D03*
X311299D03*
X315799Y55350D03*
X290999Y67550D03*
X300700Y39400D03*
X304500Y44500D03*
X305100Y39700D03*
X294100Y28000D03*
X308900Y41000D03*
X308800Y46400D03*
X306100Y126500D03*
X332200Y94200D03*
X283599Y106250D03*
X274700Y131500D03*
X280999Y120050D03*
X289999Y72550D03*
X288499Y76550D03*
X289499Y80550D03*
X308499Y72550D03*
X303999Y74050D03*
X307999Y78550D03*
X343799Y204550D03*
X321799Y173950D03*
X343399Y161350D03*
X307199Y205550D03*
X317499Y192950D03*
X331499Y193250D03*
X262699Y208550D03*
X262299Y164050D03*
X280999Y152050D03*
X343999Y190050D03*
X337999Y219050D03*
X310499Y216550D03*
X290999Y216050D03*
X271999D03*
X325499Y249450D03*
X313199Y270350D03*
X297999Y245050D03*
X283499D03*
X265999D03*
X343499Y253550D03*
X337499Y282550D03*
X313000Y313900D03*
X316999Y312576D03*
X279998Y308614D03*
Y304114D03*
Y299614D03*
Y295114D03*
X267498Y310114D03*
Y305114D03*
Y300114D03*
Y295114D03*
X276299Y376050D03*
X299899Y376650D03*
X328799Y372350D03*
X339399Y358050D03*
X289399Y395750D03*
X310999Y396250D03*
X338399Y395650D03*
X321748Y343299D03*
X277799Y338599D03*
X266699Y425050D03*
X336099Y417550D03*
X322099Y426850D03*
X338899Y433850D03*
X300899Y431850D03*
X328599Y442250D03*
X291599Y446150D03*
X266199Y472350D03*
X327900Y463200D03*
X306100Y462000D03*
X286999Y462050D03*
X272499Y445050D03*
X272999Y461050D03*
X269999Y415050D03*
X284499D03*
X303999Y415550D03*
X324999Y414550D03*
X277999Y545350D03*
X329999Y510450D03*
X298599Y501250D03*
X309399Y513450D03*
X321999Y533150D03*
X297599Y519350D03*
X340799Y512050D03*
X341399Y535850D03*
Y558950D03*
X331999Y555050D03*
Y540550D03*
X307499Y555550D03*
Y541050D03*
X281999Y529550D03*
Y512050D03*
Y497550D03*
X321999Y550550D03*
X297499Y551050D03*
X333499Y483050D03*
X312499Y484050D03*
X292999Y483550D03*
X321299Y565250D03*
X296199Y568550D03*
X320799Y582050D03*
X340299Y586550D03*
X342199Y613050D03*
X328599Y602450D03*
X302899Y607950D03*
X328499Y635650D03*
X317999Y627850D03*
X342099Y646350D03*
X280999Y608550D03*
Y591050D03*
Y576550D03*
X331999Y572550D03*
X307499Y573050D03*
X331999Y646550D03*
X307499Y647050D03*
X293999Y630550D03*
Y616050D03*
X269499Y631050D03*
Y616550D03*
X341899Y664950D03*
X342599Y678850D03*
X341399Y715050D03*
X330799Y712450D03*
X324599Y696150D03*
X297699Y681850D03*
X296399Y716950D03*
X308899Y705150D03*
X298399Y703450D03*
X331999Y678550D03*
Y661050D03*
X307499Y679050D03*
Y661550D03*
X293999Y648050D03*
X269499Y648550D03*
X268499Y716550D03*
Y711550D03*
Y701550D03*
Y706550D03*
X280999Y717550D03*
X280433Y713590D03*
X280999Y701550D03*
Y705550D03*
X338099Y811650D03*
X307999Y803150D03*
X307899Y794550D03*
X287799Y794850D03*
X268099Y795450D03*
X275299Y806350D03*
X315000Y754500D03*
X338599Y821650D03*
X318999Y814350D03*
X338599Y840450D03*
X325599Y823950D03*
X283599Y857450D03*
X293899Y843850D03*
X304899Y856150D03*
X315199Y869450D03*
X323099Y885050D03*
X340099Y887350D03*
X330299Y871850D03*
X323799Y859850D03*
X313499Y847850D03*
X300199Y835250D03*
X288899Y820550D03*
X264999Y858450D03*
X280999Y843050D03*
Y827550D03*
X264999Y842550D03*
X264499Y829050D03*
X297499Y884050D03*
Y868550D03*
X281499Y883550D03*
X280999Y870050D03*
X265799Y901850D03*
X274299Y912950D03*
X310699Y943550D03*
X323499Y956950D03*
X329799Y970650D03*
X331099Y923650D03*
X322099Y913650D03*
X302499Y899050D03*
X321099Y899650D03*
X338399Y901050D03*
X340099Y910350D03*
X340399Y931250D03*
X340099Y952850D03*
X328099Y937250D03*
X315199Y925950D03*
X302199Y914650D03*
X287299Y901050D03*
X269599Y923950D03*
X267199Y935350D03*
X264799Y946850D03*
X263299Y959350D03*
X281099Y943550D03*
X278799Y956150D03*
X277599Y975250D03*
X290099Y948650D03*
X289399Y963350D03*
X288099Y971250D03*
X299399Y965950D03*
X298099Y977250D03*
X307999Y970650D03*
X272999Y965550D03*
X333099Y983450D03*
X285399Y982950D03*
X294699Y989550D03*
X306699Y981250D03*
X304399Y997550D03*
X320999Y997250D03*
X331299Y1017150D03*
X331599Y1028750D03*
X329599Y1040750D03*
X321299Y1012450D03*
Y1024750D03*
X318299Y1038750D03*
X329599Y1057050D03*
X317699Y1054650D03*
X299999Y1052350D03*
X289699Y1021750D03*
X298399Y1008150D03*
X287099Y1000150D03*
X306399Y1020750D03*
X303699Y1038050D03*
X304699Y1057050D03*
X287099Y1035050D03*
X275099Y1024750D03*
X262499Y995850D03*
X269999Y1052550D03*
Y1037050D03*
X274999Y1012050D03*
Y996550D03*
X272999Y981050D03*
X339599Y1081550D03*
X319999Y1066950D03*
X274900Y1115600D03*
X262499Y1129150D03*
X272999Y1102850D03*
X312299Y1093550D03*
X276299Y1134550D03*
X290699Y1122650D03*
X329299Y1098550D03*
X326599Y1112350D03*
X307999Y1142050D03*
X299499Y1113550D03*
Y1098050D03*
X283499Y1113050D03*
X282999Y1099550D03*
X332999Y1138550D03*
Y1123050D03*
X317999Y1137550D03*
X316499Y1124550D03*
X283299Y1144850D03*
X323999Y1153250D03*
X304499Y1156650D03*
X313499Y1170150D03*
X291399Y1174150D03*
X300699Y1185150D03*
X279799Y1191750D03*
X286599Y1203750D03*
X315408Y1202663D03*
X329799Y1182750D03*
X311999Y1213850D03*
X300699Y1227350D03*
X272999Y1214150D03*
X326649Y1218850D03*
X328999Y1200550D03*
X272499Y1153050D03*
X268499D03*
X263999D03*
X271999Y1161550D03*
X267999D03*
X263499D03*
X333349Y1307000D03*
X310299Y1240050D03*
X264800Y1261300D03*
X283799Y1249250D03*
X304699Y1265850D03*
X312499Y1280350D03*
X300499Y1305350D03*
X274299Y1276450D03*
X295399Y1292950D03*
X281099Y1302850D03*
X333349Y1288900D03*
Y1270500D03*
X327999Y1255050D03*
X326649Y1227850D03*
X333349Y1332800D03*
X311500Y1316300D03*
X264799Y1313850D03*
X286799Y1326450D03*
X297899Y1336150D03*
X298099Y1357250D03*
X265299Y1339650D03*
X263699Y1359550D03*
X301699Y1377950D03*
X278799Y1386250D03*
X265499Y1376950D03*
X343599Y1360050D03*
X344399Y1338150D03*
X313600Y1391300D03*
X312900Y1366900D03*
X333349Y1363500D03*
X311900Y1344900D03*
X286499Y1364050D03*
Y1345050D03*
X301699Y1395750D03*
X268499Y1453550D03*
X278000Y1422000D03*
X270599Y1408550D03*
X303499Y1411250D03*
X300899Y1433350D03*
X286600Y1449700D03*
X304699Y1457550D03*
X344099Y1449550D03*
Y1421150D03*
Y1393750D03*
X313600Y1442700D03*
X312800Y1467400D03*
X333349Y1429500D03*
X312100Y1420700D03*
X285499Y1418550D03*
Y1427550D03*
Y1399550D03*
X333349Y1393100D03*
Y1481900D03*
X332500Y1519700D03*
X296599Y1497150D03*
X312000Y1514600D03*
X286700Y1516100D03*
X267349Y1518150D03*
Y1522550D03*
X266999Y1512550D03*
X267349Y1527172D03*
X279499Y1510550D03*
Y1515050D03*
X279075Y1525957D03*
X278567Y1529925D03*
X307000Y1619600D03*
X344500Y1583600D03*
X337199Y1636350D03*
X278499Y1621550D03*
X265700Y1635100D03*
X289000Y1641800D03*
X320299Y1642950D03*
X316799Y1657450D03*
X302399Y1662950D03*
X284300Y1676900D03*
X334399Y1691650D03*
X329999Y1716950D03*
X291099Y1707450D03*
X335767Y1662735D03*
X318499Y1675550D03*
X299999Y1696050D03*
X270999Y1660550D03*
X273499Y1694050D03*
X280499Y1718550D03*
X320999Y1706050D03*
X303999Y1722050D03*
X343899Y1752650D03*
X297099Y1733850D03*
X270599Y1748950D03*
X290699Y1760750D03*
X286599Y1791850D03*
X327299D03*
X322299Y1802150D03*
X303999Y1800850D03*
X270599Y1801450D03*
X263499Y1734550D03*
X285499Y1742550D03*
X321999Y1733050D03*
X303499Y1753550D03*
X321499Y1772550D03*
X334999Y1797050D03*
X326301Y1766030D03*
X315499Y1812250D03*
X284299Y1811150D03*
X270299Y1867250D03*
X337499Y1855950D03*
X316999D03*
X298999D03*
X308099Y1880550D03*
X295299Y1870250D03*
X313599Y1889250D03*
Y1870250D03*
X326399Y1876250D03*
X336799Y1888950D03*
Y1869950D03*
X283999Y1856050D03*
X306999Y1932550D03*
X302499D03*
X298499D03*
X293999Y1933050D03*
X314099Y1901250D03*
X326899Y1907250D03*
X326399Y1895250D03*
X335799Y1916450D03*
X336799Y1897950D03*
X305999Y1913050D03*
X302499Y1922050D03*
X296858Y1956228D03*
X281999Y1918550D03*
Y1923550D03*
Y1928550D03*
X266999Y1915550D03*
Y1920050D03*
Y1924550D03*
Y1929050D03*
Y1933550D03*
X326799Y1977050D03*
X329999Y1987550D03*
X311500Y1987500D03*
X291499Y1987550D03*
X272000Y1987500D03*
X381499Y65550D03*
X376999D03*
X416999Y25050D03*
X417499Y46550D03*
X416999Y63550D03*
X345499Y5050D03*
X364999Y4550D03*
X382499Y5050D03*
X395999Y5550D03*
X413499Y6050D03*
X381499Y70050D03*
X376999D03*
X381299Y136750D03*
X389599Y90950D03*
X400499Y134050D03*
Y119550D03*
X363999Y136050D03*
X417499Y79050D03*
Y93550D03*
Y108050D03*
Y125550D03*
X416999Y145050D03*
X360999Y113050D03*
X356499D03*
X351999D03*
X347499D03*
X360999Y100550D03*
X355999D03*
X350999D03*
X345999D03*
X387599Y220150D03*
X385999Y207250D03*
X354099Y175350D03*
X389299Y161650D03*
X400499Y151550D03*
X363999Y153550D03*
X369999Y219050D03*
X382499Y190550D03*
X355499Y219050D03*
X362999Y190050D03*
X416999Y164050D03*
X417999Y185050D03*
X423799Y259750D03*
X383299Y310250D03*
X386899Y299250D03*
X359399Y307250D03*
X347399Y301950D03*
X355999Y242750D03*
X347699Y269050D03*
X382999Y276650D03*
X412999Y307550D03*
Y290050D03*
Y275550D03*
X369499Y282550D03*
X381999Y254050D03*
X354999Y282550D03*
X362499Y253550D03*
X354099Y373050D03*
X368299Y386350D03*
X357999Y359050D03*
X380599Y381050D03*
X386599Y348450D03*
X394899Y357750D03*
X422499Y348150D03*
X422199Y363350D03*
X420199Y391350D03*
X419599Y458550D03*
X426599Y415350D03*
X415099Y422550D03*
X410799Y431150D03*
X354699Y426650D03*
X356399Y451750D03*
X351399Y470750D03*
X358399Y498650D03*
X357399Y521250D03*
Y530550D03*
Y543850D03*
X357999Y559450D03*
X415999Y518550D03*
X420199Y638550D03*
X427499Y624550D03*
X359399Y576050D03*
Y599650D03*
X360399Y615550D03*
X359699Y627550D03*
X345399Y698950D03*
X358899Y657150D03*
X359399Y669450D03*
X359199Y690650D03*
X357699Y707750D03*
X353999Y787750D03*
X347699Y773450D03*
X355999Y752850D03*
X424999Y766550D03*
X422999Y785050D03*
Y799550D03*
X418799Y896050D03*
Y877050D03*
X422499Y855550D03*
Y836550D03*
X422999Y817050D03*
X374500Y973500D03*
X375000Y939000D03*
Y1034000D03*
X424299Y1034050D03*
X423299Y1013050D03*
Y994050D03*
X373500Y1089500D03*
X419999Y1115550D03*
X409499Y1102550D03*
X416099Y1183550D03*
X415499Y1176050D03*
Y1161550D03*
X419499Y1219550D03*
X377499Y1210050D03*
Y1201050D03*
Y1182050D03*
X420099Y1241550D03*
X419499Y1234050D03*
X376599Y1293950D03*
X376499Y1264550D03*
Y1255550D03*
Y1236550D03*
X424999Y1278550D03*
X425499Y1290550D03*
X424999Y1259550D03*
X416699Y1342650D03*
X416199Y1367550D03*
X375599Y1323350D03*
X374499Y1375550D03*
Y1366550D03*
Y1347550D03*
X423299Y1430350D03*
X426799Y1416050D03*
X422299Y1394950D03*
X425799Y1447950D03*
X427099Y1469150D03*
X376299Y1437650D03*
X373099Y1456550D03*
X373499Y1430050D03*
Y1421050D03*
Y1402050D03*
X414799Y1532350D03*
X424299Y1541350D03*
X374099Y1554550D03*
X374799Y1491250D03*
X415999Y1603250D03*
X416199Y1625250D03*
X425499Y1635050D03*
X418299Y1561250D03*
X351899Y1570850D03*
X350600Y1610900D03*
X349099Y1634550D03*
X376099Y1572850D03*
X375099Y1608250D03*
X377700Y1629000D03*
X414799Y1653750D03*
X414399Y1678350D03*
X414499Y1707250D03*
X374999Y1656750D03*
X377099Y1696350D03*
X380099Y1709650D03*
X351099Y1691150D03*
X352000Y1700400D03*
X427499Y1662050D03*
X417799Y1790850D03*
X387899Y1802850D03*
X359499Y1736850D03*
X376799Y1734050D03*
X393499Y1759550D03*
X376499Y1775550D03*
X357999Y1796050D03*
X410757Y1772872D03*
X393999Y1784550D03*
X422999Y1778550D03*
X414499Y1810450D03*
X355699Y1810750D03*
X426499Y1855450D03*
X406999Y1855950D03*
X391499D03*
X369499D03*
X351999Y1855450D03*
X359999Y1878550D03*
X421399Y1888050D03*
X369799Y1880050D03*
X389499Y1885050D03*
X348999Y1879050D03*
X406499Y1874050D03*
X367299Y1956950D03*
X358999Y1925050D03*
X359999Y1897550D03*
Y1906550D03*
X420399Y1962550D03*
Y1934550D03*
Y1953550D03*
X421399Y1916050D03*
Y1907050D03*
X347699Y1972250D03*
X367999Y1940250D03*
X369199Y1919750D03*
X369999Y1901950D03*
X388499Y1959550D03*
Y1950550D03*
Y1932950D03*
X389499Y1913050D03*
Y1904050D03*
X349499Y1910050D03*
X348499Y1956550D03*
X347999Y1944550D03*
Y1925550D03*
X348999Y1898050D03*
X406999Y1905050D03*
X405999Y1951550D03*
X405499Y1939550D03*
Y1920550D03*
X406499Y1893050D03*
X385099Y1975950D03*
X420799Y1977250D03*
X399299Y1976750D03*
X367299Y1972950D03*
X420500Y1987000D03*
X403500D03*
X364999Y1987050D03*
X382499Y1987550D03*
X345499D03*
X436499Y50350D03*
Y31350D03*
X466799Y64750D03*
X465799Y43750D03*
Y24750D03*
X499999Y64050D03*
X500499Y47050D03*
X499999Y25550D03*
X432999Y6050D03*
X448499D03*
X467999Y5550D03*
X485499Y6050D03*
X498999D03*
X437499Y71350D03*
X442799Y142450D03*
X441799Y121450D03*
Y102450D03*
X471399Y124550D03*
X470399Y103550D03*
Y84550D03*
X473099Y141050D03*
X499999Y145550D03*
X500499Y126050D03*
Y108550D03*
Y79550D03*
Y94050D03*
X502899Y217150D03*
X504199Y193250D03*
X472999Y214550D03*
X483599Y179350D03*
X446799Y205650D03*
X445799Y184650D03*
Y165650D03*
X474099Y181050D03*
X473099Y160050D03*
X449999Y217050D03*
X430499D03*
X499999Y164550D03*
X466399Y304950D03*
X479299Y297250D03*
X437499Y307050D03*
Y289550D03*
Y275050D03*
X444499Y283050D03*
X463999Y283550D03*
X481499D03*
X495999D03*
X448999Y255550D03*
X469999Y254550D03*
X508499Y255050D03*
X488999Y254550D03*
X438999Y381550D03*
X458499Y382050D03*
X484900Y394700D03*
X485000Y373200D03*
X509999Y382550D03*
X443499Y354050D03*
X464499Y353050D03*
X502999Y353550D03*
X483499Y353050D03*
X498399Y470050D03*
X503699Y419250D03*
X472499Y458050D03*
X468799Y414250D03*
X443199Y440850D03*
X440099Y459250D03*
X431099Y479350D03*
X450300Y404200D03*
X490499Y464050D03*
X490999Y444550D03*
Y427050D03*
Y412550D03*
X454499Y472550D03*
X454999Y438550D03*
X454499Y458050D03*
X453999Y417550D03*
X430099Y551450D03*
X485299Y534550D03*
X508699Y498950D03*
X471499Y493950D03*
X452499Y565050D03*
X456499Y518050D03*
X435499Y519050D03*
X491499Y504050D03*
X490499Y483050D03*
X453999Y509550D03*
X454499Y490050D03*
X504499Y598050D03*
Y580550D03*
Y566050D03*
X479999Y598550D03*
Y581050D03*
Y566550D03*
X509999Y640550D03*
X452499Y597050D03*
Y579550D03*
X427999Y597550D03*
Y580050D03*
Y565550D03*
X506599Y711650D03*
X487299Y716950D03*
X451099Y711650D03*
X450399Y672750D03*
X444799Y687350D03*
X509999Y672550D03*
Y655050D03*
X488499Y691050D03*
Y673550D03*
Y659050D03*
X463999Y691550D03*
Y674050D03*
Y659550D03*
X467699Y772750D03*
X468699Y788350D03*
X472999Y736550D03*
X489599Y752450D03*
X490299Y734550D03*
X453399Y807950D03*
X452099Y781450D03*
Y762450D03*
X435299Y795150D03*
Y777650D03*
Y763150D03*
X437299Y744650D03*
X495999Y795050D03*
X475699Y880450D03*
X479599Y847550D03*
X462999Y884050D03*
Y865050D03*
X453399Y826950D03*
X434799Y833650D03*
Y814650D03*
X464499Y896050D03*
X493499Y884050D03*
Y865050D03*
X493999Y845550D03*
Y813550D03*
Y828050D03*
X506899Y919950D03*
Y900950D03*
X443599Y945650D03*
X442599Y924650D03*
Y905650D03*
X486799Y941050D03*
X485799Y920050D03*
Y901050D03*
X461999Y966050D03*
X462499Y946550D03*
Y914550D03*
Y929050D03*
X494099Y1017350D03*
X493099Y996350D03*
X462499Y1043850D03*
X461999Y985050D03*
X474499Y1115050D03*
X491999Y1115550D03*
X454999D03*
X439499D03*
X501499Y1102550D03*
X463999Y1102050D03*
X481499Y1102550D03*
X444499D03*
X428999D03*
X436999Y1142550D03*
Y1128050D03*
X504399Y1132250D03*
X473099Y1144550D03*
X453499Y1140550D03*
X484499Y1085850D03*
X483499Y1064850D03*
X433599Y1085550D03*
X432599Y1064550D03*
X463499Y1083850D03*
X462499Y1062850D03*
X437599Y1150050D03*
X487099Y1218050D03*
X486499Y1210550D03*
Y1196050D03*
X443199Y1224250D03*
X507199Y1224350D03*
X506599Y1202350D03*
Y1216850D03*
X505399Y1153250D03*
X474099Y1165550D03*
X454499Y1161550D03*
X443799Y1274250D03*
Y1246250D03*
Y1265250D03*
X443199Y1238750D03*
X507199Y1252350D03*
Y1243350D03*
X465499Y1284550D03*
Y1293550D03*
Y1265550D03*
X498299Y1323350D03*
X468999Y1323950D03*
X428499Y1325350D03*
X508599Y1370550D03*
X444899Y1377950D03*
X434499Y1360250D03*
X448099Y1341250D03*
X473999Y1342450D03*
X485599Y1367550D03*
X468699Y1362850D03*
X466699Y1378150D03*
X498899Y1386450D03*
X499199Y1350550D03*
X459699Y1468050D03*
X464199Y1401450D03*
X459999Y1424050D03*
X498899Y1408350D03*
X500899Y1434350D03*
X505899Y1466250D03*
X482599Y1449950D03*
X456399Y1445950D03*
X445099Y1464250D03*
X478299Y1464850D03*
X481499Y1417050D03*
Y1402550D03*
X441499Y1431550D03*
Y1414050D03*
Y1399550D03*
X499699Y1538950D03*
X466999Y1530650D03*
X488299Y1531050D03*
X461399Y1541650D03*
X474299Y1544750D03*
X452199Y1550650D03*
X444299Y1532650D03*
X439599Y1552150D03*
X465999Y1603450D03*
X487099Y1606250D03*
X449199Y1579050D03*
X443799Y1612250D03*
X460199Y1632850D03*
X484999Y1636550D03*
X501399Y1634550D03*
X508199Y1610450D03*
X510100Y1579800D03*
X472299Y1572050D03*
X502199Y1566250D03*
X472499Y1620550D03*
Y1611550D03*
X484200Y1579900D03*
X432499Y1617550D03*
X434500Y1579500D03*
X431999Y1605550D03*
X435300Y1715300D03*
X448399Y1699450D03*
X447699Y1682850D03*
X449599Y1656950D03*
X483599Y1662550D03*
X485599Y1694850D03*
X502899Y1709650D03*
X507399Y1683350D03*
X509199Y1660550D03*
X468499Y1712550D03*
X467999Y1687050D03*
Y1696050D03*
Y1668050D03*
X432400Y1680100D03*
X428600Y1691200D03*
X436799Y1772550D03*
X472699Y1792150D03*
X429499Y1748050D03*
X458499Y1742050D03*
X441499Y1758050D03*
X480999Y1756050D03*
X463999Y1772050D03*
X445499Y1792550D03*
X508200Y1758200D03*
X484999Y1779050D03*
X496999Y1799550D03*
X481299Y1811150D03*
X448099Y1809450D03*
X499999Y1854950D03*
X480499Y1855450D03*
X464999D03*
X443999Y1855950D03*
X476199Y1877450D03*
X434299Y1876050D03*
X446999Y1880050D03*
X492999Y1878050D03*
X504799Y1967550D03*
Y1939550D03*
Y1958550D03*
X505799Y1921050D03*
Y1912050D03*
Y1893050D03*
X475199Y1951950D03*
Y1923950D03*
Y1942950D03*
X476199Y1905450D03*
Y1896450D03*
X459299Y1966850D03*
Y1938850D03*
Y1957850D03*
X460299Y1920350D03*
Y1911350D03*
Y1892350D03*
X433299Y1950550D03*
Y1922550D03*
Y1941550D03*
X434299Y1904050D03*
Y1895050D03*
X445999Y1954550D03*
Y1945550D03*
Y1926550D03*
X446999Y1908050D03*
Y1899050D03*
X493499Y1909050D03*
X492499Y1955550D03*
X491999Y1943550D03*
Y1924550D03*
X492999Y1897050D03*
X509299Y1977250D03*
X493799D03*
X473299D03*
X455799Y1976750D03*
X436299Y1977250D03*
X492500Y1987500D03*
X476000Y1987000D03*
X456500Y1987500D03*
X438999Y1987550D03*
X522899Y64350D03*
Y45350D03*
X587999Y63550D03*
X588499Y46550D03*
X587999Y25050D03*
X541499Y63550D03*
X541999Y46550D03*
X541499Y25050D03*
X516499Y6550D03*
X535999D03*
X551499D03*
X570999Y6050D03*
X588499Y6550D03*
X523899Y85350D03*
X520299Y141450D03*
Y122450D03*
X569099Y112550D03*
X568099Y91550D03*
Y72550D03*
X562799Y146750D03*
Y127750D03*
X587999Y145050D03*
X588499Y125550D03*
X541499Y145050D03*
X541999Y125550D03*
Y108050D03*
Y79050D03*
Y93550D03*
X565999Y199950D03*
X528799D03*
X521299Y162450D03*
X563799Y167750D03*
X587999Y217050D03*
X568499Y217550D03*
X552999D03*
X533499D03*
X588999Y185050D03*
X587999Y164050D03*
X542499Y185050D03*
X541499Y164050D03*
X544799Y293950D03*
X540099Y306550D03*
X516899Y306950D03*
X515499Y284050D03*
X536499Y283050D03*
X525999Y255050D03*
X540499D03*
X572999Y287050D03*
X572499Y306550D03*
X572999Y269550D03*
Y255050D03*
X558099Y335050D03*
X557933Y331010D03*
X557999Y322550D03*
Y326550D03*
X579899Y375750D03*
X530999Y381550D03*
X520499Y353550D03*
X548100Y362200D03*
X573499Y346550D03*
X572499Y325550D03*
X577899Y460550D03*
X578399Y441050D03*
X577399Y420050D03*
X539799Y466050D03*
X538799Y445050D03*
X576099Y481850D03*
X511299Y449150D03*
X519499Y471550D03*
X518999Y416550D03*
X592499Y478050D03*
Y459050D03*
X592999Y439550D03*
Y422050D03*
Y407550D03*
X556499Y467550D03*
X555999Y412550D03*
X539299Y485550D03*
X576599Y522350D03*
X577099Y502850D03*
X579499Y561550D03*
X558499Y562550D03*
X538999Y562050D03*
X535499Y545050D03*
X514499Y546050D03*
X518999Y508550D03*
X519499Y489050D03*
X555999Y504550D03*
X556499Y485050D03*
X558499Y616050D03*
X554304Y615840D03*
X554499Y624550D03*
X558699D03*
X554499Y620050D03*
X558709Y620245D03*
X534499Y640050D03*
X586299Y711250D03*
X565699Y710650D03*
X549999Y710050D03*
X547999Y728550D03*
X573499Y690550D03*
Y673050D03*
Y658550D03*
X534499Y672050D03*
Y654550D03*
Y805950D03*
X511199Y782050D03*
X527499Y747150D03*
X525499Y772450D03*
X547499Y799050D03*
Y780050D03*
X547999Y760550D03*
Y743050D03*
X575499Y802050D03*
X575999Y782550D03*
Y765050D03*
X577999Y732050D03*
X575999Y750550D03*
X526499Y851150D03*
X510899Y868150D03*
X578299Y895650D03*
X541399Y873450D03*
Y854450D03*
X512899Y842550D03*
Y823550D03*
X521999Y895550D03*
X522499Y876050D03*
X576499Y842050D03*
X575499Y821050D03*
X583299Y961450D03*
X578299Y914650D03*
X540299Y956850D03*
X539299Y935850D03*
X570899Y965850D03*
Y946850D03*
X521999Y914550D03*
X562999Y898050D03*
X560499Y968050D03*
X560999Y948550D03*
Y916550D03*
Y931050D03*
X516499Y957050D03*
X514499Y975550D03*
X583299Y980450D03*
X534599Y1048550D03*
X571899Y986850D03*
X573499Y1055550D03*
Y1036550D03*
X541899Y1021450D03*
X540899Y1000450D03*
Y981450D03*
X560499Y987050D03*
X560999Y999050D03*
X558999Y1049550D03*
Y1017550D03*
Y1032050D03*
X513999Y1046050D03*
Y1027050D03*
X514499Y1007550D03*
Y990050D03*
X588499Y1101550D03*
X578999Y1114550D03*
X568499Y1101550D03*
X564499Y1116050D03*
X548999D03*
X529499D03*
X511999Y1115550D03*
X553999Y1103050D03*
X538499D03*
X518999D03*
X535599Y1069550D03*
X574499Y1076550D03*
X558499Y1088050D03*
Y1069050D03*
X547099Y1202750D03*
Y1221750D03*
X546499Y1180750D03*
Y1195250D03*
X567999Y1215550D03*
Y1206550D03*
Y1187550D03*
X527999Y1212550D03*
X527499Y1200550D03*
Y1181550D03*
X579299Y1300750D03*
X527499Y1278150D03*
X530499Y1297050D03*
X561099Y1301050D03*
X566399Y1273850D03*
X549399Y1302850D03*
Y1274850D03*
Y1293850D03*
X548799Y1252850D03*
Y1267350D03*
X547099Y1230750D03*
X583299Y1283250D03*
Y1255250D03*
Y1274250D03*
X582699Y1233250D03*
Y1247750D03*
X565999Y1248550D03*
Y1234050D03*
X525999Y1263050D03*
Y1245550D03*
Y1231050D03*
X555699Y1322950D03*
X581999Y1370150D03*
X559099Y1343250D03*
X545099Y1355250D03*
X518499Y1346950D03*
X540399Y1382150D03*
X523999Y1391050D03*
X523499Y1360050D03*
Y1379050D03*
X580999Y1412750D03*
X575699Y1438950D03*
X538799Y1409750D03*
X536799Y1436350D03*
X528499Y1460250D03*
X546099Y1467550D03*
X582999Y1461250D03*
X557499Y1443050D03*
Y1452050D03*
Y1424050D03*
X516999Y1437050D03*
X517499Y1449050D03*
X516999Y1418050D03*
X563499Y1497550D03*
Y1486550D03*
Y1503550D03*
Y1492050D03*
X590599Y1483450D03*
X529799Y1555050D03*
X567999Y1549950D03*
X582299Y1534150D03*
X538999Y1528350D03*
X518899Y1530150D03*
X532499Y1635550D03*
X552099Y1601950D03*
X553399Y1624550D03*
X590799Y1627850D03*
X588000Y1604000D03*
X588099Y1572050D03*
X552199Y1576650D03*
X569499Y1619550D03*
Y1610550D03*
X573400Y1577600D03*
X529499Y1616550D03*
X533800Y1575500D03*
X528999Y1604550D03*
X518499Y1643950D03*
X538299Y1721050D03*
X532599Y1655650D03*
X554199Y1651950D03*
X555199Y1674750D03*
X555399Y1689350D03*
X555899Y1706750D03*
X580299Y1722550D03*
X590599Y1694450D03*
X580799Y1646150D03*
X572999Y1694550D03*
Y1703550D03*
Y1675550D03*
X532499Y1688550D03*
X532999Y1700550D03*
X532499Y1669550D03*
X582599Y1740050D03*
X560399Y1792550D03*
X555500Y1802700D03*
X539499Y1788150D03*
X526499Y1801150D03*
X556199Y1727050D03*
X522300Y1739200D03*
X532499Y1763050D03*
X515499Y1779050D03*
X544300Y1784638D03*
X531799Y1818450D03*
X514199Y1815750D03*
X591499Y1855950D03*
X573999Y1855450D03*
X554499Y1855950D03*
X538999D03*
X517499Y1855450D03*
X588899Y1882350D03*
X562599Y1874450D03*
X519399Y1876750D03*
X533499Y1884050D03*
X575999Y1888050D03*
X587899Y1956850D03*
Y1928850D03*
Y1947850D03*
X588899Y1910350D03*
Y1901350D03*
X561599Y1948950D03*
Y1920950D03*
Y1939950D03*
X562599Y1902450D03*
Y1893450D03*
X546999Y1966850D03*
Y1938850D03*
Y1957850D03*
X547999Y1920350D03*
Y1911350D03*
Y1892350D03*
X518399Y1951250D03*
Y1923250D03*
Y1942250D03*
X519399Y1904750D03*
Y1895750D03*
X532499Y1958550D03*
Y1949550D03*
Y1930550D03*
X533499Y1912050D03*
Y1903050D03*
X575999Y1907050D03*
X576499Y1919050D03*
X574999Y1953550D03*
X575499Y1965550D03*
X574999Y1934550D03*
X585799Y1976250D03*
X570299D03*
X546299Y1977250D03*
X528799Y1976750D03*
X568999Y1987050D03*
X553499D03*
X588499Y1986550D03*
X511999Y1987550D03*
X531500Y1987500D03*
X603999Y54350D03*
Y35350D03*
X651799Y59650D03*
Y40650D03*
X674999Y59050D03*
X675499Y42050D03*
X674999Y20550D03*
X624499Y61550D03*
X624999Y44550D03*
X624499Y23050D03*
X608499Y6550D03*
X625999Y7050D03*
X645499D03*
X660999D03*
X604999Y75350D03*
X603999Y133750D03*
X652799Y80650D03*
X649899Y138350D03*
X674999Y140550D03*
X675499Y121050D03*
Y103550D03*
Y74550D03*
Y89050D03*
X624499Y143050D03*
X624999Y123550D03*
X623899Y202550D03*
X604999Y173750D03*
X603999Y152750D03*
X650899Y178350D03*
X649899Y157350D03*
X662499Y218050D03*
X642999D03*
X625499Y217550D03*
X605499D03*
X675999Y180550D03*
X674999Y159550D03*
X625499Y183050D03*
X624499Y162050D03*
X656499Y307050D03*
X653999Y286550D03*
X627999Y280050D03*
X627499Y299550D03*
X627999Y262550D03*
Y248050D03*
X599799Y385150D03*
X600299Y365650D03*
X599299Y344650D03*
X659899Y363250D03*
X632399Y358750D03*
X635399Y376250D03*
X607399Y380250D03*
X643599Y395950D03*
X655999Y344050D03*
X656499Y324550D03*
X628499Y339550D03*
X628200Y320000D03*
X644099Y450950D03*
X644599Y416950D03*
X644099Y436450D03*
X621499Y466550D03*
X621999Y432550D03*
X621499Y452050D03*
X620999Y411550D03*
X666999Y476550D03*
X643499Y546750D03*
X642499Y525750D03*
X613700Y504600D03*
X621499Y484050D03*
X593499Y499050D03*
X666499Y547050D03*
X666999Y508550D03*
X666499Y528050D03*
X666999Y491050D03*
X642999Y566250D03*
X640599Y604650D03*
X673999Y645150D03*
X645099Y639150D03*
X631999Y639650D03*
X665999Y623550D03*
X620499D03*
Y609050D03*
X595999Y641550D03*
Y624050D03*
Y609550D03*
X674999Y601550D03*
X646999Y584550D03*
X625999Y585050D03*
X606499Y584550D03*
X667499Y568050D03*
X651999Y718350D03*
X648999Y702350D03*
X629099Y714050D03*
X605299Y661750D03*
X609499Y708050D03*
X607499Y726550D03*
X647499Y689050D03*
Y671550D03*
Y657050D03*
X622999Y689550D03*
Y672050D03*
X597999Y690050D03*
X647399Y742150D03*
X653099Y803350D03*
X621499Y767150D03*
X633499Y750150D03*
X606999Y797050D03*
Y778050D03*
X607499Y758550D03*
Y741050D03*
X664999Y805050D03*
Y786050D03*
X665499Y766550D03*
X645799Y816650D03*
X642599Y883250D03*
X641599Y862250D03*
Y843250D03*
X621999Y835050D03*
X612999Y854550D03*
X629499Y853050D03*
Y868550D03*
X613499Y868050D03*
X663499Y896050D03*
X663999Y876550D03*
Y844550D03*
Y859050D03*
X665999Y826050D03*
X639499Y971150D03*
Y952150D03*
X616699Y967250D03*
Y948250D03*
X658999Y959050D03*
X656999Y977550D03*
X603499Y904050D03*
X601499Y954550D03*
Y922550D03*
Y937050D03*
X664499Y936050D03*
X663499Y915050D03*
X673999Y1036550D03*
Y1017550D03*
X674699Y1061450D03*
X611399Y1045650D03*
Y1026650D03*
X617699Y988250D03*
X656499Y1048050D03*
Y1029050D03*
X656999Y1009550D03*
Y992050D03*
X631999Y1001550D03*
X629999Y1052050D03*
Y1020050D03*
Y1034550D03*
X600999Y1002050D03*
X598999Y1052550D03*
Y1020550D03*
Y1035050D03*
X633999Y1103050D03*
X669499Y1116550D03*
X616499Y1115050D03*
X605999Y1102050D03*
X598999Y1114550D03*
X674699Y1080450D03*
X674999Y1134950D03*
X641799Y1137650D03*
X627699Y1143550D03*
X612399Y1066650D03*
X629499Y1090550D03*
Y1071550D03*
X598499Y1091050D03*
Y1072050D03*
X603899Y1157850D03*
X626199Y1183450D03*
X597599Y1196050D03*
X596599Y1215050D03*
X651599Y1203050D03*
X650599Y1182050D03*
X651299Y1174150D03*
X650299Y1153150D03*
X668199Y1173850D03*
X667199Y1152850D03*
X671199Y1213750D03*
X670199Y1192750D03*
X628699Y1164550D03*
X668699Y1227650D03*
X672999Y1303450D03*
X608899Y1305050D03*
X600899Y1238650D03*
X630499Y1243950D03*
X657099Y1272850D03*
X657799Y1288450D03*
X656399Y1307050D03*
X618199Y1296250D03*
Y1268250D03*
Y1287250D03*
X617599Y1246250D03*
Y1260750D03*
X638999Y1286550D03*
Y1295550D03*
Y1267550D03*
X598499Y1280550D03*
X598999Y1292550D03*
X598499Y1261550D03*
X671999Y1324950D03*
X631799Y1322650D03*
X605599Y1326350D03*
X665699Y1337250D03*
X606199Y1338250D03*
X617899Y1360850D03*
X625499Y1383450D03*
X632499Y1347950D03*
X599999Y1382550D03*
X599499Y1351550D03*
Y1370550D03*
X654999Y1385050D03*
X654499Y1373050D03*
Y1354050D03*
X659699Y1445950D03*
X604899Y1407750D03*
X601299Y1447650D03*
X636799Y1461250D03*
X626799Y1432350D03*
X627499Y1406050D03*
X665699Y1462250D03*
X652999Y1435550D03*
Y1418050D03*
Y1403550D03*
X656099Y1479550D03*
X625199Y1489150D03*
X610899Y1496750D03*
X672399Y1508750D03*
X673699Y1535350D03*
X662099Y1549650D03*
X643099Y1541350D03*
X599799Y1544650D03*
X617699Y1530350D03*
X670699Y1603150D03*
X671399Y1625350D03*
X628499Y1636650D03*
X633499Y1615450D03*
X635500Y1603900D03*
X652399Y1575850D03*
X623499Y1564050D03*
X652499Y1618550D03*
Y1609550D03*
X639200Y1576200D03*
X612499Y1615550D03*
X611900Y1577900D03*
X611999Y1603550D03*
X649399Y1644950D03*
X657099Y1668850D03*
X635099Y1691150D03*
X607599Y1716450D03*
X593399Y1668850D03*
X627299Y1659550D03*
X600599Y1645450D03*
X674999Y1676550D03*
X656499Y1697050D03*
X609499Y1692050D03*
Y1675050D03*
X642499Y1709050D03*
X665399Y1752350D03*
X650399Y1771250D03*
X593299Y1760950D03*
X619499Y1803150D03*
X627273Y1793905D03*
X606999Y1745550D03*
X625499Y1725050D03*
X675499Y1757050D03*
X675999Y1769050D03*
X675499Y1738050D03*
X642400Y1800100D03*
X659159Y1792278D03*
X626999Y1800050D03*
X645099Y1877550D03*
X667999Y1870950D03*
X632799Y1820450D03*
X627494Y1829068D03*
X608599Y1810750D03*
X669399Y1855350D03*
X627499Y1855950D03*
X611999D03*
X630699Y1872750D03*
X602799Y1887350D03*
X640999Y1815550D03*
X595199Y1820910D03*
X659549Y1815384D03*
X644049Y1810834D03*
X633837Y1807384D03*
X646799Y1926450D03*
X645399Y1906150D03*
X673899Y1966850D03*
Y1938850D03*
Y1957850D03*
X674899Y1920350D03*
Y1911350D03*
Y1892350D03*
X660299Y1964550D03*
Y1936550D03*
Y1955550D03*
X661299Y1918050D03*
Y1909050D03*
Y1890050D03*
X629699Y1947250D03*
Y1919250D03*
Y1938250D03*
X630699Y1900750D03*
Y1891750D03*
X601799Y1961850D03*
Y1933850D03*
Y1952850D03*
X602799Y1915350D03*
Y1906350D03*
X616499Y1913050D03*
Y1922050D03*
Y1894050D03*
X615499Y1959550D03*
Y1968550D03*
Y1940550D03*
X644999Y1953050D03*
X645499Y1965050D03*
X644999Y1934050D03*
X659299Y1976250D03*
X643799D03*
X622799D03*
X605299Y1975750D03*
X642499Y1987050D03*
X626999D03*
X661999Y1986550D03*
X605999Y1987050D03*
X751499Y48350D03*
X694999Y62650D03*
X757499Y63050D03*
Y44050D03*
X725499Y62050D03*
X725999Y45050D03*
X725499Y23550D03*
X680499Y6550D03*
X697999Y7050D03*
X712499Y6050D03*
X729999Y6550D03*
X749499D03*
X752099Y112150D03*
X738199Y137450D03*
X695999Y102650D03*
X694999Y81650D03*
X699699Y141750D03*
X758499Y84050D03*
X725499Y143550D03*
X725999Y124050D03*
Y106550D03*
Y77550D03*
Y92050D03*
X757999Y154550D03*
Y159050D03*
X753999Y154550D03*
Y159050D03*
X728899Y204550D03*
X688999Y196550D03*
X700699Y181750D03*
X699699Y160750D03*
X749499Y218550D03*
X729499D03*
X711999Y218050D03*
X677999D03*
X726499Y183550D03*
X725499Y162550D03*
X755499Y314550D03*
X751539Y313984D03*
X711999Y307550D03*
Y293050D03*
X723200Y275500D03*
X711499Y252550D03*
X680500Y280700D03*
X682999Y300050D03*
X683499Y263050D03*
Y248550D03*
X755346Y319149D03*
X751499Y318050D03*
X749899Y398550D03*
X711499Y344550D03*
X711999Y325050D03*
X683999Y340050D03*
X682999Y319050D03*
X713699Y455450D03*
X713199Y474950D03*
X712699Y434450D03*
X750399Y453550D03*
X750899Y419550D03*
X750399Y439050D03*
X694999Y480550D03*
X737999Y467050D03*
X691399Y548350D03*
X755699Y528650D03*
X756199Y509150D03*
X755199Y488150D03*
X754499Y564650D03*
X713099Y561550D03*
X713599Y542050D03*
X712599Y521050D03*
X713199Y489450D03*
X695499Y521050D03*
X695999Y501550D03*
X737999Y559050D03*
X738499Y539550D03*
Y522050D03*
Y507550D03*
X738999Y488050D03*
X691899Y588850D03*
X692399Y569350D03*
X754999Y605150D03*
X755499Y585650D03*
X717099Y636050D03*
X729699Y640350D03*
X731499Y604050D03*
Y586550D03*
Y572050D03*
X690499Y623050D03*
X744999Y626550D03*
X721499Y617550D03*
X699999Y610050D03*
X751499Y679148D03*
X749499Y716050D03*
X744999Y715550D03*
X749999Y720050D03*
X745499D03*
X757400Y686300D03*
X720899Y712250D03*
X732499Y729250D03*
X681899Y713650D03*
X679299Y703050D03*
X727099Y715050D03*
X739399Y688150D03*
X747999Y670750D03*
X723499Y654850D03*
X693999Y648150D03*
X754999Y694050D03*
X702999Y688050D03*
Y670550D03*
Y656050D03*
X678499Y688550D03*
Y671050D03*
X749999Y700050D03*
X710899Y751150D03*
X696299Y741850D03*
X685999Y780050D03*
X694599Y763450D03*
X743099Y785350D03*
X733799Y761450D03*
X716599Y736850D03*
X723999Y802350D03*
Y783350D03*
X687099Y804650D03*
X706999Y811550D03*
Y792550D03*
X707499Y773050D03*
X728499Y841850D03*
X724999Y823350D03*
X688099Y844650D03*
X687099Y823650D03*
X729999Y881850D03*
Y862850D03*
X751599Y887350D03*
X705999Y851050D03*
Y865550D03*
X707999Y832550D03*
X751499Y855550D03*
Y836550D03*
X751999Y817050D03*
X707399Y918550D03*
Y899550D03*
X678299Y978350D03*
X730999Y902850D03*
X688099Y936350D03*
X687099Y915350D03*
Y896350D03*
X724699Y976250D03*
X723699Y955250D03*
Y936250D03*
X752599Y927350D03*
X751599Y906350D03*
X706499Y942550D03*
X749999Y965550D03*
Y946550D03*
X751399Y1023550D03*
Y1004550D03*
X752399Y1052550D03*
X734999Y1030550D03*
Y1045050D03*
X713999Y1049050D03*
Y1031550D03*
Y1017050D03*
X678299Y997350D03*
X694999Y993050D03*
X692999Y1043550D03*
Y1011550D03*
Y1026050D03*
X750999Y986550D03*
X755499Y1119050D03*
X749999Y1119550D03*
X748999Y1115550D03*
X748499Y1111550D03*
X734999Y1062550D03*
X713499Y1068550D03*
X737999Y1119050D03*
X727499Y1106050D03*
X720499Y1118550D03*
X709999Y1105550D03*
X700499Y1118550D03*
X689999Y1105550D03*
X727499Y1132650D03*
X704299D03*
X692499Y1082050D03*
Y1063050D03*
X753999Y1100050D03*
X713599Y1214650D03*
X756799Y1217650D03*
X758799Y1190150D03*
Y1199150D03*
X717999Y1169150D03*
X716999Y1148150D03*
X714399Y1199750D03*
X713399Y1178750D03*
X735999Y1220550D03*
Y1206050D03*
X737999Y1187550D03*
Y1178550D03*
Y1159550D03*
X695999Y1217550D03*
Y1203050D03*
X697999Y1184550D03*
X697499Y1172550D03*
Y1153550D03*
X684299Y1249550D03*
X740799Y1298750D03*
X723499Y1292650D03*
Y1278150D03*
X725499Y1250650D03*
Y1259650D03*
Y1231650D03*
X755399Y1300650D03*
Y1286150D03*
X757399Y1258650D03*
Y1267650D03*
Y1239650D03*
X756799Y1232150D03*
X709699Y1264550D03*
X708699Y1243550D03*
X740499Y1252550D03*
Y1270050D03*
X695999Y1235050D03*
X739199Y1348950D03*
X742099Y1320650D03*
X719199Y1322350D03*
X695999Y1323350D03*
X677999Y1347550D03*
X680299Y1365850D03*
X713899Y1386450D03*
X707899Y1346250D03*
X734199Y1373850D03*
X694999Y1388050D03*
Y1379050D03*
Y1360050D03*
X702299Y1404450D03*
X736199Y1399050D03*
X741099Y1450250D03*
X737799Y1428350D03*
X716899Y1459850D03*
X700899Y1450250D03*
X681299Y1393150D03*
X678299Y1425050D03*
X686999Y1468850D03*
X719499Y1446650D03*
X721899Y1419050D03*
X754999Y1420050D03*
Y1437550D03*
X692999Y1421050D03*
Y1406550D03*
X751000Y1517000D03*
X757500Y1522500D03*
X751000Y1521000D03*
Y1525000D03*
X741099Y1498150D03*
X729199Y1492750D03*
X716199Y1503050D03*
X735799Y1533650D03*
X714599Y1533950D03*
X708899Y1549250D03*
X685299Y1551950D03*
X747199Y1509150D03*
X755499Y1507550D03*
X734499Y1563550D03*
X722199Y1564250D03*
X706700Y1579900D03*
X698599Y1568550D03*
X681299Y1579150D03*
X693599Y1602450D03*
X686699Y1638650D03*
X742000Y1560000D03*
X743400Y1578700D03*
X719999Y1605050D03*
X751300Y1604900D03*
X732999Y1620050D03*
X756299Y1679050D03*
X738799Y1677250D03*
X750099Y1694950D03*
X756499Y1712150D03*
X739199Y1716750D03*
X721199Y1723750D03*
X727399Y1694350D03*
X717099Y1702450D03*
X693099Y1722350D03*
X691999Y1660550D03*
X751999Y1775550D03*
X756617Y1780067D03*
X752657Y1779496D03*
X755999Y1775550D03*
X756900Y1766000D03*
X753558Y1769946D03*
X757518Y1770517D03*
X752900Y1766000D03*
X751899Y1752150D03*
X747799Y1766750D03*
X729499Y1778750D03*
X729999Y1756450D03*
X747499Y1734350D03*
X702599Y1730550D03*
X709099Y1751850D03*
X690499Y1744950D03*
X694599Y1768450D03*
X715999Y1763050D03*
Y1772050D03*
Y1744050D03*
X693549Y1793134D03*
X706549Y1793634D03*
X744049Y1791634D03*
X740549Y1802634D03*
X753949Y1798194D03*
X705000Y1811900D03*
X686999Y1870250D03*
X728099Y1844750D03*
X747599Y1844250D03*
X743799Y1888850D03*
X728299D03*
X753699Y1879250D03*
X732199Y1878750D03*
X744699Y1868450D03*
X758399Y1868350D03*
X723199Y1867950D03*
X743399Y1855850D03*
X725899Y1855350D03*
X690899Y1855850D03*
X706399D03*
X697999Y1844550D03*
X732999Y1868550D03*
X711500Y1817700D03*
X704300Y1828400D03*
X686473Y1818375D03*
X740549Y1810384D03*
X696299Y1898850D03*
X716599Y1918450D03*
X728799Y1933050D03*
X709199Y1962950D03*
X698299Y1948050D03*
X676399Y1901150D03*
X695299Y1926450D03*
X711899Y1944050D03*
X736799Y1919450D03*
X728799Y1908150D03*
X705599Y1891850D03*
X730499Y1954650D03*
X755299Y1902150D03*
X739799D03*
X685499Y1959050D03*
Y1968050D03*
Y1940050D03*
X755500Y1914500D03*
X721499Y1974550D03*
X696299Y1976250D03*
X678799Y1975750D03*
X754999Y1987550D03*
X737499Y1987050D03*
X717999Y1987550D03*
X702499D03*
X679499Y1987050D03*
X774399Y54050D03*
X763399Y24150D03*
X817599Y43750D03*
X824899Y25150D03*
X813299Y68350D03*
Y49350D03*
X796999Y65550D03*
X797499Y48550D03*
X796999Y27050D03*
X764999Y6550D03*
X784499Y6050D03*
X801999Y6550D03*
X818999Y6050D03*
X836499Y6550D03*
X840499Y55050D03*
X839999Y46050D03*
X840999Y62550D03*
X778399Y105250D03*
X775399Y80250D03*
X821199Y137450D03*
X813299Y110850D03*
X805899Y126150D03*
X767399Y140150D03*
X796599Y123450D03*
X814299Y89350D03*
X796999Y147050D03*
X797499Y127550D03*
Y110050D03*
Y81050D03*
Y95550D03*
X837499Y138550D03*
X838499Y145050D03*
X837999Y91050D03*
X838999Y85050D03*
X838499Y99550D03*
Y107050D03*
X839499Y119050D03*
X841499Y71550D03*
X760799Y181950D03*
X779399Y200550D03*
X786499Y219050D03*
X800999Y216550D03*
X766999Y219050D03*
X797999Y187050D03*
X796999Y166050D03*
X838999Y313550D03*
X821499Y314050D03*
X809373Y307571D03*
Y297571D03*
Y292571D03*
X808999Y303050D03*
X796873Y307571D03*
Y303071D03*
Y298571D03*
Y294071D03*
X839299Y390950D03*
X819299Y394250D03*
X838499Y352050D03*
X840299Y430950D03*
X839299Y409950D03*
X820299Y434250D03*
X819299Y413250D03*
X802999Y466050D03*
X774999Y476550D03*
Y462050D03*
X825399Y540950D03*
X825899Y521450D03*
X824899Y500450D03*
X835599Y564050D03*
X834599Y543050D03*
X802999Y558050D03*
X803499Y538550D03*
Y521050D03*
Y506550D03*
X803999Y487050D03*
X775499Y553550D03*
X774499Y532550D03*
X774999Y494050D03*
X774499Y513550D03*
X835099Y583550D03*
X814499Y601550D03*
Y584050D03*
Y569550D03*
X789999Y602050D03*
Y584550D03*
Y570050D03*
X785499Y641050D03*
X777499Y638050D03*
X771800Y686600D03*
X786500Y686100D03*
X798000Y686400D03*
X764599Y655750D03*
X777499Y664550D03*
X794999D03*
X806300Y670600D03*
X841000Y671100D03*
X766499Y699050D03*
X782999Y699550D03*
X836149Y714050D03*
X766499Y705550D03*
X806831Y701853D03*
Y706853D03*
Y711853D03*
X794331Y698353D03*
Y702853D03*
Y707353D03*
Y711853D03*
X806999Y697050D03*
X799385Y761436D03*
X778999Y806950D03*
X763099Y796350D03*
X835999Y799050D03*
Y781550D03*
Y767050D03*
X811499Y799550D03*
Y782050D03*
Y767550D03*
X837799Y754150D03*
X825199Y850850D03*
X827699Y892450D03*
Y873450D03*
X776199Y879250D03*
X775199Y858250D03*
Y839250D03*
X800999Y892550D03*
X802999Y874050D03*
X801999Y853050D03*
Y834050D03*
X802499Y814550D03*
X828699Y913450D03*
X826999Y963150D03*
X773199Y960650D03*
X772199Y939650D03*
Y920650D03*
X800499Y944050D03*
Y963050D03*
X800999Y924550D03*
Y907050D03*
Y1037550D03*
Y1005550D03*
Y1020050D03*
X827999Y1003150D03*
X826999Y982150D03*
X777899Y1028050D03*
X776899Y1007050D03*
Y988050D03*
X801499Y984050D03*
X783999Y1096550D03*
X760999Y1095550D03*
X789499Y1099550D03*
X773499Y1101050D03*
X769499D03*
X773499Y1105050D03*
X769499D03*
X836149Y1118550D03*
X811499Y1097050D03*
X807499D03*
X807341Y1116216D03*
Y1111216D03*
Y1101216D03*
X806999Y1106050D03*
X802499Y1097566D03*
X798499D03*
X808299Y1175850D03*
X806599Y1189750D03*
X803599Y1211050D03*
X831499Y1209550D03*
Y1200550D03*
Y1181550D03*
X789499Y1225050D03*
X791499Y1206550D03*
X790999Y1194550D03*
Y1175550D03*
X839999Y1157550D03*
X826199Y1294450D03*
X828199Y1267850D03*
X788999Y1278150D03*
X791999Y1294450D03*
X808199Y1290350D03*
Y1275850D03*
X810199Y1248350D03*
Y1257350D03*
Y1229350D03*
X829499Y1242550D03*
Y1228050D03*
X789499Y1257050D03*
Y1239550D03*
X825500Y1379000D03*
X831499Y1324950D03*
X795299Y1326650D03*
X822199Y1335250D03*
X819199Y1353550D03*
X798299Y1344250D03*
X779399Y1361850D03*
X762499Y1335550D03*
Y1353050D03*
X799999Y1340550D03*
Y1358050D03*
X806499Y1390550D03*
X803299Y1426650D03*
X773999Y1393450D03*
X763399Y1401450D03*
X781999Y1434650D03*
X805899Y1464250D03*
X771399Y1474550D03*
X806499Y1408050D03*
X834499Y1397550D03*
X836600Y1416500D03*
X769300Y1488100D03*
X779000Y1488400D03*
X786500Y1488600D03*
X801300Y1489000D03*
X770999Y1500050D03*
X780499D03*
X839499Y1523550D03*
X773499Y1509050D03*
X769499D03*
X786999Y1506550D03*
X809245Y1518722D03*
Y1508722D03*
Y1503722D03*
X795999Y1518550D03*
Y1514050D03*
Y1509550D03*
Y1504550D03*
X808999Y1513550D03*
X813300Y1604100D03*
X827199Y1622750D03*
X841499Y1638950D03*
X803599Y1618350D03*
X826499Y1609050D03*
X825999Y1578050D03*
X839899Y1562050D03*
X829200Y1719800D03*
X824100Y1719900D03*
X819400Y1721900D03*
X837199Y1660550D03*
X814599Y1642650D03*
X776999Y1647650D03*
X797299Y1646650D03*
X802899Y1670550D03*
X839199Y1683550D03*
X808899Y1698450D03*
X779999Y1717050D03*
X770399Y1699650D03*
X765099Y1664950D03*
X823499Y1693050D03*
Y1702050D03*
Y1674050D03*
X782999Y1687050D03*
X783499Y1699050D03*
X782999Y1668050D03*
X819200Y1727100D03*
X808299Y1755250D03*
X794499Y1734550D03*
X770099Y1730350D03*
X779899Y1748150D03*
X787900Y1758800D03*
X765600Y1756800D03*
X827999Y1791550D03*
X767159Y1792364D03*
X829799Y1856350D03*
X809299D03*
X791799Y1855850D03*
X801099Y1844750D03*
X785599D03*
X765099D03*
X780799Y1888850D03*
X763299Y1888350D03*
X833100Y1878500D03*
X806199Y1879250D03*
X788699Y1878750D03*
X769199Y1879250D03*
X833199Y1868450D03*
X818900Y1870800D03*
X797199Y1868450D03*
X779699Y1867950D03*
X779399Y1855850D03*
X763899D03*
X773999Y1923550D03*
X767999Y1923050D03*
X774499Y1930050D03*
X768999D03*
X783499Y1907050D03*
X774499Y1908050D03*
X765999D03*
X838999Y1928550D03*
X790499Y1913050D03*
X775999Y1916050D03*
X840999Y1970550D03*
X768499Y1917550D03*
X795526Y1909696D03*
X795493Y1913696D03*
X795501Y1917696D03*
X795499Y1922050D03*
X807997Y1922865D03*
X808005Y1918865D03*
X807936Y1914865D03*
Y1910365D03*
X813599Y1979950D03*
X789299Y1983850D03*
X829499Y1980250D03*
X829999Y1987550D03*
X812499Y1987050D03*
X792999Y1987550D03*
X777499D03*
X844799Y19850D03*
X860799Y24150D03*
X885999Y21150D03*
X855999Y6550D03*
X871499D03*
X890999Y6050D03*
X908499Y6550D03*
X923999Y6050D03*
X854499Y39550D03*
X865499D03*
X883999Y39050D03*
X904999Y61550D03*
Y67550D03*
X905499Y56550D03*
X890700Y132500D03*
X872100Y132700D03*
X854300Y132600D03*
X891999Y146050D03*
X843499Y82550D03*
X855499Y82050D03*
X876999D03*
X867499D03*
X845999Y111050D03*
X886499Y99550D03*
Y104550D03*
X890459Y100116D03*
X890499Y104550D03*
X865499Y125550D03*
X875499D03*
X856499Y71050D03*
X881499Y70550D03*
X866999D03*
X904499Y74050D03*
X906999Y224150D03*
X887400Y233555D03*
X871786Y233924D03*
Y218924D03*
Y203924D03*
X907999Y264150D03*
X906999Y243150D03*
X906399Y314250D03*
Y295250D03*
X863999Y313550D03*
X887400Y259700D03*
X879878Y247724D03*
X907399Y335250D03*
X875799Y386250D03*
X904999Y385050D03*
Y370550D03*
X854499Y387550D03*
Y373050D03*
X858400Y352300D03*
X847999Y352550D03*
X870600Y346700D03*
X876799Y426250D03*
X875799Y405250D03*
X884399Y462450D03*
Y443450D03*
X905499Y462050D03*
X904499Y441050D03*
Y422050D03*
X904999Y402550D03*
X854999Y464550D03*
X853999Y443550D03*
X854499Y405050D03*
X853999Y424550D03*
X861199Y546050D03*
X860199Y525050D03*
X885399Y483450D03*
X914699Y524650D03*
X913699Y503650D03*
Y484650D03*
X860699Y565550D03*
X898999Y622050D03*
Y604550D03*
X860499Y607550D03*
X861800Y591200D03*
X918999Y641550D03*
X870719Y609705D03*
X894000Y642400D03*
X870719Y639705D03*
X870773Y624705D03*
X903999Y574378D03*
X866499Y724550D03*
X895999Y720050D03*
Y702550D03*
X900999Y670050D03*
Y652550D03*
X918499Y712050D03*
X918999Y673550D03*
X918499Y693050D03*
X918999Y656050D03*
X887401Y665000D03*
X881200Y652100D03*
X859999Y713050D03*
X871385Y719436D03*
X871786Y709482D03*
X871499Y689436D03*
X871786Y679436D03*
X860796Y678632D03*
X921399Y796350D03*
X921899Y776850D03*
Y759350D03*
Y744850D03*
X884499Y799050D03*
Y781550D03*
Y767050D03*
X859999Y799550D03*
Y782050D03*
Y767550D03*
X919499Y733050D03*
X856299Y753150D03*
X846799Y754150D03*
X865000Y752100D03*
X889699Y876050D03*
X847799Y828250D03*
X857099Y873450D03*
X920399Y886850D03*
Y869350D03*
Y854850D03*
X922399Y836350D03*
X921399Y815350D03*
X898499Y862050D03*
Y844550D03*
Y830050D03*
X873999Y862550D03*
Y845050D03*
Y830550D03*
X886999Y947250D03*
Y907350D03*
X867199Y941350D03*
X866199Y920350D03*
Y901350D03*
X850999Y962550D03*
Y943550D03*
X919899Y925350D03*
X920899Y946350D03*
X919899Y906350D03*
X851999Y983550D03*
X921499Y1031050D03*
X920999Y1050550D03*
X921499Y1013550D03*
Y999050D03*
X870468Y1030227D03*
X880033Y1058592D03*
X886919Y1044478D03*
X870298Y1045227D03*
X870777Y1014948D03*
X921999Y1090550D03*
X920999Y1069550D03*
X887400Y1070600D03*
X859999Y1118550D03*
X841999D03*
X845799Y1190450D03*
X849799Y1199750D03*
X846499Y1170450D03*
X897299Y1182450D03*
X887999Y1209350D03*
X871399Y1201850D03*
Y1210850D03*
Y1182850D03*
X892499Y1224550D03*
X851999Y1218550D03*
X856400Y1157700D03*
X848999Y1158050D03*
X863300Y1153800D03*
X872099Y1268150D03*
X871399Y1291450D03*
X860099Y1295450D03*
X869399Y1243850D03*
Y1229350D03*
X890499Y1285550D03*
Y1271050D03*
X892499Y1252550D03*
Y1243550D03*
X850499Y1300050D03*
Y1282550D03*
Y1268050D03*
X852499Y1249550D03*
X851999Y1237550D03*
X875399Y1322650D03*
X868499Y1392550D03*
X890999Y1336550D03*
Y1354050D03*
X841999Y1341050D03*
Y1358550D03*
X873499Y1356050D03*
X894499Y1423550D03*
Y1441050D03*
X868499Y1410050D03*
X886913Y1449010D03*
X879727Y1463696D03*
X871836Y1450460D03*
Y1435460D03*
Y1420460D03*
X914599Y1521650D03*
X910899Y1549250D03*
X894499Y1522050D03*
Y1539550D03*
X895499Y1488050D03*
X902759Y1509585D03*
X861999Y1522550D03*
X843999Y1523550D03*
X887499Y1476050D03*
X865300Y1557700D03*
X923599Y1634350D03*
X909700Y1576400D03*
X907500Y1604000D03*
X908899Y1630050D03*
X868099Y1635650D03*
X887299Y1620050D03*
X886900Y1604100D03*
X873099Y1572550D03*
X850099Y1572250D03*
X849900Y1605100D03*
X852499Y1621350D03*
X866499Y1603050D03*
Y1612050D03*
X864000Y1578200D03*
X858400Y1561900D03*
X850499Y1562050D03*
X879200Y1698700D03*
X879900Y1709300D03*
X883900Y1709500D03*
X855350Y1703201D03*
X914899Y1657550D03*
X922599Y1682150D03*
X903599Y1686850D03*
X895999Y1661250D03*
X877699Y1646650D03*
X855799Y1658250D03*
X882999Y1678250D03*
X864099Y1683550D03*
X842799Y1701150D03*
X875900Y1709500D03*
X902900Y1709800D03*
X842500Y1799000D03*
X892700Y1727800D03*
X879399Y1798150D03*
X911299Y1800850D03*
X864000Y1748000D03*
X866699Y1770950D03*
X853799Y1790850D03*
X844499Y1788050D03*
X892700Y1736500D03*
X904814Y1789113D03*
X863099Y1813150D03*
X903299Y1814750D03*
X894999Y1829050D03*
X922899Y1853650D03*
X905299Y1852650D03*
X900299Y1876950D03*
X842199Y1879250D03*
X914999Y1887050D03*
Y1868050D03*
X862499Y1823550D03*
X854977Y1818994D03*
X887401Y1881500D03*
X894000Y1868452D03*
X887499Y1855550D03*
X869999Y1855972D03*
X871836Y1840972D03*
X869634Y1826876D03*
X864414Y1940050D03*
X914899Y1912450D03*
X916599Y1942650D03*
X897599Y1938750D03*
X914899Y1972250D03*
X873399Y1963650D03*
X904299Y1954950D03*
X897299Y1904150D03*
X907599Y1930050D03*
X915499Y1899050D03*
X861414Y1928550D03*
X843999D03*
X856999Y1970050D03*
X849999Y1970550D03*
X865200Y1968000D03*
X879399Y1974550D03*
X850499Y1977950D03*
X868699Y1983250D03*
X921499Y1986550D03*
X901999Y1987050D03*
X864999D03*
X849499D03*
X884499Y1986550D03*
X974699Y64650D03*
X977399Y44050D03*
X954799Y17850D03*
X974699Y21450D03*
X991399Y22450D03*
X1002699Y40050D03*
X991999Y56050D03*
X941499Y6550D03*
X960999D03*
X976499D03*
X995999Y6050D03*
X967499Y47050D03*
Y56050D03*
Y64050D03*
X945499Y33550D03*
X940499Y33050D03*
X929999Y32550D03*
X928499Y51550D03*
X943499Y48050D03*
Y55050D03*
X928999Y56050D03*
X928499Y60550D03*
X928999Y65550D03*
X942999Y61550D03*
Y66550D03*
X983099Y83650D03*
X1005299Y71350D03*
X977699Y109150D03*
X994399Y101250D03*
X981099Y123450D03*
X939199Y142050D03*
X968399Y137150D03*
X967999Y73050D03*
Y82050D03*
X943499Y72550D03*
Y78050D03*
X988699Y174350D03*
X967399Y180350D03*
X956099Y181350D03*
X958799Y167350D03*
X1004799Y231450D03*
X1005299Y211950D03*
Y194450D03*
Y179950D03*
X952799Y231150D03*
Y213650D03*
Y199150D03*
X982999Y203550D03*
Y221050D03*
Y189050D03*
X932499Y223550D03*
Y206050D03*
Y191550D03*
X1005299Y305450D03*
Y290950D03*
X1005799Y271450D03*
X1004799Y250450D03*
X952799Y310150D03*
X953299Y290650D03*
X952299Y269650D03*
Y250650D03*
X983999Y316050D03*
Y301550D03*
X933499Y304050D03*
X983499Y280550D03*
X982499Y259550D03*
Y240550D03*
X932999Y283050D03*
X931999Y262050D03*
Y243050D03*
X1005799Y382450D03*
X1004799Y361450D03*
X1005299Y322950D03*
X1004799Y342450D03*
X952299Y380650D03*
X952799Y342150D03*
X952299Y361650D03*
X952799Y324650D03*
X984499Y393050D03*
X983499Y372050D03*
Y353050D03*
X983999Y333550D03*
X933999Y395550D03*
X932999Y374550D03*
X933499Y336050D03*
X932999Y355550D03*
X933499Y318550D03*
X966199Y473350D03*
X1000699Y482350D03*
Y463350D03*
X954799Y451650D03*
Y434150D03*
Y419650D03*
X953299Y401650D03*
X983499Y464050D03*
X983999Y427050D03*
Y444550D03*
Y412550D03*
X933499Y447050D03*
X932999Y466550D03*
X933499Y429550D03*
Y415050D03*
X967199Y513350D03*
X966199Y492350D03*
X1001699Y503350D03*
X1003499Y546350D03*
X1003999Y526850D03*
X951299Y560150D03*
Y541150D03*
X951799Y521650D03*
Y504150D03*
Y489650D03*
X985999Y536550D03*
Y554050D03*
Y522050D03*
X935499Y556550D03*
Y539050D03*
Y524550D03*
X984499Y504050D03*
X983499Y483050D03*
X933999Y506550D03*
X932999Y485550D03*
X967799Y606350D03*
X966799Y585350D03*
Y566350D03*
X1005999Y636350D03*
Y618850D03*
X1004499Y586350D03*
X1005999Y604350D03*
X1003499Y565350D03*
X950299Y631650D03*
Y614150D03*
Y599650D03*
X952299Y581150D03*
X969499Y639050D03*
X986499Y613550D03*
X985499Y592550D03*
Y573550D03*
X935999Y616050D03*
X934999Y595050D03*
Y576050D03*
X949799Y670150D03*
X950799Y691150D03*
X949799Y651150D03*
X969999Y730550D03*
X968999Y709550D03*
Y690550D03*
X969499Y653550D03*
Y671050D03*
Y795750D03*
X969999Y776250D03*
Y758750D03*
Y744250D03*
X994499Y803550D03*
Y784550D03*
X994999Y747550D03*
Y765050D03*
Y733050D03*
X943999Y806050D03*
X944499Y767550D03*
X943999Y787050D03*
X944499Y750050D03*
Y735550D03*
X970499Y879750D03*
Y862250D03*
Y847750D03*
Y835750D03*
X969499Y814750D03*
X992999Y894550D03*
X993499Y857550D03*
Y875050D03*
Y843050D03*
X942999Y877550D03*
Y860050D03*
Y845550D03*
X995499Y824550D03*
X944999Y827050D03*
X994499Y973550D03*
Y956050D03*
Y941550D03*
X949299Y977450D03*
X970999Y939250D03*
X969999Y918250D03*
Y899250D03*
X993999Y934550D03*
X992999Y913550D03*
X943499Y937050D03*
X942499Y916050D03*
Y897050D03*
X994999Y1033050D03*
Y1045050D03*
X993999Y1012050D03*
Y993050D03*
X948799Y1047950D03*
Y1028950D03*
X949299Y1009450D03*
Y991950D03*
X971499Y1048050D03*
X971999Y1011050D03*
Y1028550D03*
Y996550D03*
X949799Y1068950D03*
Y1080950D03*
X998599Y1128450D03*
Y1110950D03*
Y1096450D03*
X950699Y1139750D03*
Y1122250D03*
Y1107750D03*
X975999Y1115550D03*
Y1133050D03*
Y1101050D03*
X925499Y1135550D03*
Y1118050D03*
Y1103550D03*
X972499Y1088050D03*
X971499Y1067050D03*
X999099Y1214450D03*
Y1199950D03*
Y1187950D03*
X998099Y1147950D03*
Y1166950D03*
X951199Y1225750D03*
Y1211250D03*
Y1199250D03*
X950199Y1159250D03*
Y1178250D03*
X976499Y1219050D03*
Y1204550D03*
X925999Y1221550D03*
Y1207050D03*
X976499Y1192550D03*
X975499Y1171550D03*
Y1152550D03*
X925999Y1195050D03*
X924999Y1174050D03*
Y1155050D03*
X999599Y1291450D03*
X998599Y1270450D03*
Y1251450D03*
X999099Y1231950D03*
X951699Y1302750D03*
X950699Y1281750D03*
Y1262750D03*
X951199Y1243250D03*
X976999Y1296050D03*
X975999Y1275050D03*
Y1256050D03*
X976499Y1236550D03*
X926499Y1298550D03*
X925499Y1277550D03*
X925999Y1239050D03*
X925499Y1258550D03*
X975100Y1342600D03*
X1000700Y1358100D03*
X996500Y1324800D03*
X952499Y1361850D03*
X944000Y1391900D03*
X943799Y1380850D03*
Y1342950D03*
X965099Y1324350D03*
X928499Y1325350D03*
X976499Y1377050D03*
Y1362550D03*
X925999Y1379550D03*
Y1365050D03*
X992500Y1397300D03*
X964400Y1409700D03*
X946700Y1426500D03*
X994200Y1421500D03*
X924999Y1471050D03*
X926499Y1456550D03*
X925499Y1435550D03*
X925999Y1397050D03*
X925499Y1416550D03*
X973200Y1516400D03*
X972500Y1529100D03*
X966600D03*
X961400Y1528700D03*
X961900Y1522400D03*
X967100Y1522800D03*
X973000D03*
X962100Y1516000D03*
X967300Y1516400D03*
X972700Y1534800D03*
X972000Y1547500D03*
X966100D03*
X960900Y1547100D03*
X961400Y1540800D03*
X966600Y1541200D03*
X972500D03*
X961600Y1534400D03*
X966800Y1534800D03*
X972700Y1553300D03*
X961600Y1552900D03*
X966800Y1553300D03*
X944000Y1511300D03*
X943199Y1531650D03*
X924499Y1541550D03*
X924999Y1503050D03*
X924499Y1522550D03*
X924999Y1485550D03*
X972000Y1566000D03*
X966100D03*
X960900Y1565600D03*
X961400Y1559300D03*
X966600Y1559700D03*
X972500D03*
X973000Y1572800D03*
X972300Y1585500D03*
X966400D03*
X961200Y1585100D03*
X961700Y1578800D03*
X966900Y1579200D03*
X972800D03*
X961900Y1572400D03*
X967100Y1572800D03*
X972400Y1592000D03*
X966500D03*
X961300Y1591600D03*
X972200Y1598400D03*
X966300D03*
X961100Y1598000D03*
X960600Y1604300D03*
X971700Y1604700D03*
X965800D03*
X944499Y1632650D03*
X925599Y1612050D03*
X933199Y1577550D03*
X925499Y1562550D03*
X950100Y1626100D03*
X989999Y1718050D03*
X958799Y1715750D03*
X957799Y1646950D03*
X955499Y1690850D03*
X941499Y1679550D03*
X940499Y1656950D03*
X931499Y1702050D03*
X941800Y1787700D03*
X934200Y1793500D03*
X993299Y1734350D03*
X994999Y1748950D03*
X976600Y1757100D03*
X965349Y1742000D03*
X949799Y1756250D03*
X976399Y1772250D03*
X954499Y1783550D03*
X941499Y1776250D03*
X932199Y1801850D03*
X971000Y1803000D03*
X999999Y1775250D03*
X976399Y1791150D03*
X993499Y1805550D03*
X928000Y1818500D03*
X1003599Y1846650D03*
X995699Y1858950D03*
X971500Y1871500D03*
X937199Y1869950D03*
X993499Y1824550D03*
Y1833550D03*
X987999Y1971950D03*
Y1949050D03*
X1000999Y1946350D03*
X991999Y1915750D03*
X966799Y1892150D03*
X974699Y1914450D03*
X945199Y1946350D03*
X955799Y1951950D03*
X954099Y1915450D03*
X938199Y1917150D03*
X1002500Y1953500D03*
X1001599Y1921450D03*
X992299Y1929050D03*
X989999Y1962650D03*
X980999Y1933350D03*
X947499Y1936050D03*
X946199Y1966650D03*
X937499Y1893850D03*
X971499Y1956050D03*
Y1965050D03*
Y1937050D03*
X930999Y1950050D03*
X931499Y1962050D03*
X930999Y1931050D03*
X955499Y1893050D03*
Y1902050D03*
X953799Y1977950D03*
X930199Y1979550D03*
X1005000Y1980500D03*
X994999Y1986550D03*
X973999D03*
X956499Y1986050D03*
X936999Y1986550D03*
X1022000Y15500D03*
X1013499Y6550D03*
X1020499Y50550D03*
X1020999Y33050D03*
X1010599Y115550D03*
X1020499Y122550D03*
X1020999Y105050D03*
Y85550D03*
Y70050D03*
X1021499Y141050D03*
X1020999Y230550D03*
X1021499Y213050D03*
Y193550D03*
Y178050D03*
X1020999Y158550D03*
Y304550D03*
Y289050D03*
X1020499Y269550D03*
X1020999Y252050D03*
X1020499Y341550D03*
X1020999Y324050D03*
X1020499Y391550D03*
X1020999Y374050D03*
X1007299Y432450D03*
Y414950D03*
Y400450D03*
X1020499Y463550D03*
X1020999Y446050D03*
Y426550D03*
Y411050D03*
X1021999Y558550D03*
Y539050D03*
Y523550D03*
X1021499Y504050D03*
X1021999Y486550D03*
X1021499Y576050D03*
X1020999Y642550D03*
X1020499Y623050D03*
X1020999Y605550D03*
X1020499Y695050D03*
X1020999Y677550D03*
Y658050D03*
Y720050D03*
X1020499Y809550D03*
X1020999Y792050D03*
Y772550D03*
Y757050D03*
X1020499Y737550D03*
Y880550D03*
Y865050D03*
X1019999Y845550D03*
X1020499Y828050D03*
X1019999Y917550D03*
X1020499Y900050D03*
X1019999Y971050D03*
X1019499Y951550D03*
X1019999Y934050D03*
Y986550D03*
Y1058550D03*
Y1043050D03*
X1019499Y1023550D03*
X1019999Y1006050D03*
X1020499Y1134050D03*
Y1118550D03*
X1019999Y1099050D03*
X1020499Y1081550D03*
X1019499Y1198550D03*
Y1183050D03*
X1018999Y1163550D03*
X1019499Y1146050D03*
X1016999Y1219050D03*
X1016499Y1301050D03*
Y1236550D03*
X1016999Y1256050D03*
Y1271550D03*
X1023300Y1344400D03*
X1024300Y1365200D03*
X1022599Y1322950D03*
X1024300Y1393600D03*
X1008599Y1716050D03*
X1022299Y1715750D03*
X1008999Y1702450D03*
X1016899Y1731650D03*
X1026899Y1768550D03*
X1020299Y1746650D03*
X1015299Y1765950D03*
X1009999Y1797450D03*
X1022499Y1802050D03*
X1022999Y1784550D03*
X1011299Y1860650D03*
X1007599Y1818450D03*
X1022999Y1821550D03*
Y1837050D03*
X1020499Y1877550D03*
X1020999Y1860050D03*
Y1912550D03*
Y1897050D03*
X1017499Y1954550D03*
X1017999Y1937050D03*
Y1987050D03*
X1023000Y1973000D03*
G54D13*
X6500Y1098000D03*
Y1103500D03*
Y1110000D03*
Y1116500D03*
X32400Y115400D03*
X37000Y115300D03*
X32300Y121000D03*
X36900Y120900D03*
X32100Y130700D03*
X37000D03*
X32100Y136600D03*
X36800Y136700D03*
X36500Y179000D03*
Y188500D03*
X35000Y198500D03*
X30000Y179000D03*
X23500D03*
X30000Y188500D03*
X24000D03*
X29000Y198000D03*
X23500D03*
X44000Y728500D03*
X40000Y729000D03*
X44500Y733000D03*
X40000D03*
X43999Y737550D03*
X39999Y738050D03*
X44499Y742050D03*
X39999D03*
X22500Y1183000D03*
Y1176500D03*
Y1170000D03*
Y1164500D03*
X83499Y1602050D03*
X92499Y1589050D03*
X86999D03*
X83499Y1594050D03*
Y1598050D03*
X74999Y1602050D03*
X78999D03*
X81499Y1589050D03*
X78999Y1593550D03*
X74999Y1598050D03*
Y1593550D03*
X78999Y1598050D03*
X165500Y416500D03*
X150500Y545000D03*
X172000Y931600D03*
X110999Y1130550D03*
X115200Y1130300D03*
X110999Y1126050D03*
Y1122050D03*
Y1118050D03*
X114999Y1126050D03*
Y1122050D03*
Y1118050D03*
X127000Y1202000D03*
X148000Y1206000D03*
X144149Y1226113D03*
Y1222113D03*
X148499D03*
Y1226113D03*
X144149Y1230113D03*
X148486D03*
X143700Y1332500D03*
X174250Y1694500D03*
X132700Y1972400D03*
X137900Y1972200D03*
X126500Y1972400D03*
X132700Y1978600D03*
X137900Y1978400D03*
X126600Y1978500D03*
X119999Y1978550D03*
X119499Y1972550D03*
X189499Y39150D03*
X197999Y39900D03*
X193999D03*
X208499Y45650D03*
X199999Y46050D03*
X194499Y44050D03*
X247800Y269700D03*
X179999Y442550D03*
X179649Y438550D03*
X183999D03*
Y442550D03*
Y447050D03*
X179999D03*
X246800Y677100D03*
X204496Y846111D03*
X204649Y838050D03*
X208999D03*
X209000Y846113D03*
X204649Y842113D03*
X208986D03*
X247500Y1085500D03*
X224750Y1483950D03*
X195000Y1645500D03*
X231800Y1887100D03*
X323400Y105200D03*
X305998Y352114D03*
X293998Y361114D03*
Y356614D03*
Y352114D03*
X289998Y361114D03*
Y356614D03*
Y352114D03*
X294999Y767050D03*
X290999D03*
X294999Y762550D03*
Y758050D03*
X290999Y762550D03*
Y758050D03*
X306999D03*
X305998Y1569114D03*
X293998Y1578114D03*
Y1573614D03*
Y1569114D03*
X289998Y1578114D03*
Y1573614D03*
Y1569114D03*
X333000Y1578000D03*
X306000Y1961500D03*
X305500Y1965500D03*
X293999Y1971050D03*
Y1966550D03*
Y1962050D03*
X289499Y1961550D03*
Y1966550D03*
Y1971050D03*
X330500Y1966500D03*
X748000Y357500D03*
X750000Y755500D03*
X747000Y1159000D03*
X750000Y1560500D03*
X717000Y1812384D03*
X750000Y1965500D03*
X827500Y274500D03*
X784478Y355424D03*
Y359924D03*
X781478Y363924D03*
X776978D03*
X772478Y359924D03*
Y363924D03*
X829800Y666650D03*
X771196Y764382D03*
Y760382D03*
X775696Y764382D03*
X780196D03*
X783196Y760382D03*
Y755882D03*
X825700Y1083100D03*
X783333Y1157392D03*
Y1161892D03*
X780333Y1165892D03*
X775833D03*
X771333Y1161892D03*
Y1165892D03*
X827700Y1487600D03*
X785827Y1561296D03*
Y1565796D03*
X782827Y1569796D03*
X778327D03*
X773327Y1565796D03*
X773827Y1569796D03*
X828500Y1877800D03*
X783814Y1967213D03*
Y1971713D03*
X784016Y1975708D03*
X775814Y1975699D03*
X771814Y1975713D03*
X902999Y22050D03*
X917499Y21550D03*
X909499D03*
X902499Y35050D03*
X909999Y35550D03*
X916499Y36050D03*
X973500Y1474000D03*
X971500Y1467500D03*
X971700Y1457800D03*
Y1462300D03*
X972000Y1442000D03*
Y1437500D03*
X971700Y1448300D03*
Y1452800D03*
X962500Y1436500D03*
Y1441000D03*
X952800Y1437500D03*
Y1442000D03*
X962000Y1466500D03*
X966000Y1475000D03*
X952300Y1467500D03*
X958800Y1472500D03*
X962200Y1447300D03*
Y1451800D03*
X952500Y1448300D03*
Y1452800D03*
X962200Y1456800D03*
Y1461300D03*
X952500Y1457800D03*
Y1462300D03*
X972549Y1502300D03*
Y1506800D03*
X973500Y1483000D03*
Y1478500D03*
X973200Y1488300D03*
X972700Y1497300D03*
X966000Y1479500D03*
Y1484000D03*
X958800Y1477000D03*
Y1481500D03*
X965700Y1489300D03*
X960200Y1495300D03*
X958500Y1486800D03*
X951500Y1495300D03*
X960049Y1500300D03*
X951349D03*
X960049Y1504800D03*
X951349D03*
G54D17*
X78150Y28858D03*
Y178464D03*
Y434370D03*
Y583976D03*
Y839882D03*
Y989488D03*
Y1245394D03*
Y1395000D03*
Y1650906D03*
Y1800512D03*
X158071Y191614D03*
Y341220D03*
Y597126D03*
Y746732D03*
Y1002638D03*
Y1152244D03*
Y1408150D03*
Y1557756D03*
Y1813662D03*
Y1963268D03*
X886417Y191614D03*
Y341220D03*
Y597126D03*
Y746732D03*
Y1002638D03*
Y1152244D03*
Y1408150D03*
Y1557756D03*
Y1813662D03*
Y1963268D03*
G54D10*
X-39052Y28742D03*
X-43327Y310478D03*
X-39686Y917251D03*
X-38801Y1082342D03*
X-44886Y1294251D03*
X-43103Y1928864D03*
X1071932Y32074D03*
X1074813Y1348051D03*
X1076613Y1740651D03*
X1074813Y1957551D03*
G54D15*
X17720Y1903144D03*
X29532Y309561D03*
Y1029522D03*
X271657Y267711D03*
Y673223D03*
Y1078734D03*
Y1484246D03*
Y1889758D03*
X994098Y149601D03*
Y673223D03*
X994099Y1068892D03*
G54D12*
X9843Y153168D03*
Y265767D03*
Y353144D03*
Y717711D03*
Y762617D03*
Y875216D03*
Y1137420D03*
Y1250019D03*
Y1337396D03*
Y1701963D03*
Y1746869D03*
Y1859468D03*
G54D21*
X1019291Y1416024D03*
Y1694212D03*
G54D18*
X129920Y17716D03*
X994093Y1889751D03*
G54D19*
X180299Y1626550D03*
X180000Y1619600D03*
X195700Y1619100D03*
X195600Y1623700D03*
X180299Y1634550D03*
X179733Y1630590D03*
X371999Y15550D03*
X376499D03*
X380999D03*
X369999Y23550D03*
Y19050D03*
X382499Y20050D03*
G54D20*
X882200Y1744800D03*
X886400Y1744400D03*
%LPC*%
G75*
G54D22*
G01X-71137Y-139897D02*
Y-219897D01*
G01D02*
X1129963D01*
G01X-75137Y-123897D02*
G02I-12000J0D01*
G01X-80287D02*
G02I-6850J0D01*
G01X-87137Y-139897D02*
Y-107897D01*
G01X-71137Y-123897D02*
X-103137D01*
G01X-71137Y-139897D02*
X1129963D01*
G01X-71137Y-175397D02*
X1129963D01*
G01X342463Y-139897D02*
Y-219897D01*
G01X479963Y-139897D02*
Y-219897D01*
G01X594963Y-139897D02*
Y-219897D01*
G01X762463Y-139897D02*
Y-219897D01*
G01X932463Y-139897D02*
Y-219897D01*
G01X1129963Y-139897D02*
Y-219897D01*
G01X1157963Y-123897D02*
G02I-12000J0D01*
G01X1152813D02*
G02I-6850J0D01*
G01X1145963Y-139897D02*
Y-107897D01*
G01X1161963Y-123897D02*
X1129963D01*
G54D23*
G01X-89222Y-207897D02*
Y-190397D01*
G01X-80052D02*
Y-207897D01*
G01Y-199147D02*
X-89222D01*
G01X-67137Y-207897D02*
X-68447Y-207605D01*
X-69757Y-206439D01*
X-70631Y-204397D01*
X-71067Y-202064D01*
X-70631Y-199730D01*
X-69757Y-197689D01*
X-68447Y-196522D01*
X-67137Y-196231D01*
X-65827Y-196522D01*
X-64517Y-197689D01*
X-63644Y-199730D01*
X-63425Y-202064D01*
X-63644Y-204397D01*
X-64517Y-206439D01*
X-65827Y-207605D01*
X-67137Y-207897D01*
G01X-53349D02*
Y-196231D01*
G01Y-199147D02*
X-52475Y-197689D01*
X-51165Y-196522D01*
X-49419Y-196231D01*
X-47891Y-196522D01*
X-46580Y-197689D01*
X-45925Y-199730D01*
Y-207897D01*
G01X-35412Y-200022D02*
X-28425D01*
X-29080Y-197980D01*
X-30172Y-196814D01*
X-31700Y-196231D01*
X-33229Y-196522D01*
X-34539Y-197397D01*
X-35412Y-199439D01*
X-35849Y-201189D01*
Y-202939D01*
X-35412Y-204689D01*
X-34320Y-206439D01*
X-33010Y-207605D01*
X-31482Y-207897D01*
X-29954Y-207314D01*
X-28425Y-205564D01*
G01X-19222Y-213147D02*
X-17912Y-213730D01*
X-16165Y-213147D01*
X-15074Y-211981D01*
X-14200Y-210522D01*
X-12891Y-205856D01*
X-10052Y-196231D01*
G01X-17039D02*
X-12891Y-205856D01*
G01X22109Y-198564D02*
X22983Y-197689D01*
X23638Y-196231D01*
X24075Y-194188D01*
X23638Y-192439D01*
X22765Y-191272D01*
X21236Y-190397D01*
X15341D01*
Y-207897D01*
X22546D01*
X24075Y-206731D01*
X24948Y-204980D01*
X25385Y-202939D01*
X24948Y-200897D01*
X23638Y-199147D01*
X22109Y-198564D01*
X15341D01*
G01X41793Y-207897D02*
Y-196231D01*
G01Y-198272D02*
X40920Y-197106D01*
X39609Y-196522D01*
X38081Y-196231D01*
X36553Y-196814D01*
X35243Y-197980D01*
X34369Y-199730D01*
X33933Y-202064D01*
X34369Y-204397D01*
X35243Y-206147D01*
X36553Y-207314D01*
X38081Y-207897D01*
X39609Y-207605D01*
X40920Y-206731D01*
X41793Y-205564D01*
G01X59293Y-190397D02*
Y-207897D01*
G01Y-205273D02*
X58420Y-206731D01*
X57109Y-207605D01*
X55581Y-207897D01*
X53835Y-207314D01*
X52525Y-205856D01*
X51651Y-204106D01*
X51433Y-202064D01*
X51651Y-200022D01*
X52525Y-198272D01*
X53835Y-196814D01*
X55581Y-196231D01*
X57109Y-196522D01*
X58201Y-197106D01*
X59293Y-198272D01*
G01X69806Y-212272D02*
X71335Y-213439D01*
X73081Y-213730D01*
X74609Y-213439D01*
X75920Y-211981D01*
X76793Y-209939D01*
Y-196231D01*
G01Y-198564D02*
X75920Y-197397D01*
X74609Y-196522D01*
X73081Y-196231D01*
X71335Y-196814D01*
X70243Y-197980D01*
X69369Y-200022D01*
X68933Y-202064D01*
X69151Y-203814D01*
X70025Y-205856D01*
X71335Y-207314D01*
X73081Y-207897D01*
X74391Y-207605D01*
X75920Y-206439D01*
X76793Y-205273D01*
G01X87088Y-200022D02*
X94075D01*
X93420Y-197980D01*
X92328Y-196814D01*
X90800Y-196231D01*
X89271Y-196522D01*
X87961Y-197397D01*
X87088Y-199439D01*
X86651Y-201189D01*
Y-202939D01*
X87088Y-204689D01*
X88180Y-206439D01*
X89490Y-207605D01*
X91018Y-207897D01*
X92546Y-207314D01*
X94075Y-205564D01*
G01X104806Y-207897D02*
Y-196231D01*
G01Y-198564D02*
X105898Y-197397D01*
X106990Y-196522D01*
X108518Y-196231D01*
X109609Y-196522D01*
X110920Y-197397D01*
G01X138060Y-207897D02*
Y-190397D01*
X142426D01*
X144173Y-191272D01*
X145483Y-192439D01*
X146575Y-194188D01*
X147448Y-196231D01*
X147666Y-199147D01*
X147448Y-202064D01*
X146575Y-204106D01*
X145483Y-205856D01*
X144173Y-207022D01*
X142426Y-207897D01*
X138060D01*
G01X155996D02*
Y-190397D01*
X161236D01*
X162983Y-191272D01*
X164293Y-193314D01*
X164730Y-195647D01*
X164293Y-197980D01*
X163201Y-199730D01*
X161236Y-200606D01*
X155996D01*
G01X179609Y-198564D02*
X180483Y-197689D01*
X181138Y-196231D01*
X181575Y-194188D01*
X181138Y-192439D01*
X180265Y-191272D01*
X178736Y-190397D01*
X172841D01*
Y-207897D01*
X180046D01*
X181575Y-206731D01*
X182448Y-204980D01*
X182885Y-202939D01*
X182448Y-200897D01*
X181138Y-199147D01*
X179609Y-198564D01*
X172841D01*
G01X208496Y-190397D02*
Y-207897D01*
X217230D01*
G01X230363D02*
X229053Y-207605D01*
X227743Y-206439D01*
X226869Y-204397D01*
X226433Y-202064D01*
X226869Y-199730D01*
X227743Y-197689D01*
X229053Y-196522D01*
X230363Y-196231D01*
X231673Y-196522D01*
X232983Y-197689D01*
X233856Y-199730D01*
X234075Y-202064D01*
X233856Y-204397D01*
X232983Y-206439D01*
X231673Y-207605D01*
X230363Y-207897D01*
G01X242404Y-196231D02*
X245025Y-207897D01*
X247863Y-196231D01*
X250701Y-207897D01*
X253322Y-196231D01*
G01X278496Y-190397D02*
Y-207897D01*
X287230D01*
G01X300363D02*
X299053Y-207605D01*
X297743Y-206439D01*
X296869Y-204397D01*
X296433Y-202064D01*
X296869Y-199730D01*
X297743Y-197689D01*
X299053Y-196522D01*
X300363Y-196231D01*
X301673Y-196522D01*
X302983Y-197689D01*
X303856Y-199730D01*
X304075Y-202064D01*
X303856Y-204397D01*
X302983Y-206439D01*
X301673Y-207605D01*
X300363Y-207897D01*
G01X314588Y-205856D02*
X315680Y-207022D01*
X317208Y-207897D01*
X318518D01*
X319828Y-207314D01*
X320701Y-206439D01*
X321138Y-205273D01*
X320920Y-203522D01*
X320046Y-202647D01*
X316116Y-200897D01*
X315243Y-198855D01*
X315680Y-197397D01*
X316553Y-196522D01*
X317863Y-196231D01*
X319173Y-196522D01*
X320483Y-197397D01*
G01X332088Y-205856D02*
X333180Y-207022D01*
X334708Y-207897D01*
X336018D01*
X337328Y-207314D01*
X338201Y-206439D01*
X338638Y-205273D01*
X338420Y-203522D01*
X337546Y-202647D01*
X333616Y-200897D01*
X332743Y-198855D01*
X333180Y-197397D01*
X334053Y-196522D01*
X335363Y-196231D01*
X336673Y-196522D01*
X337983Y-197397D01*
G01X94686Y-164897D02*
Y-147397D01*
X100363Y-161980D01*
X106040Y-147397D01*
Y-164897D01*
G01X117863D02*
X116553Y-164605D01*
X115243Y-163439D01*
X114369Y-161397D01*
X113933Y-159064D01*
X114369Y-156730D01*
X115243Y-154689D01*
X116553Y-153522D01*
X117863Y-153231D01*
X119173Y-153522D01*
X120483Y-154689D01*
X121356Y-156730D01*
X121575Y-159064D01*
X121356Y-161397D01*
X120483Y-163439D01*
X119173Y-164605D01*
X117863Y-164897D01*
G01X139293Y-147397D02*
Y-164897D01*
G01Y-162273D02*
X138420Y-163731D01*
X137109Y-164605D01*
X135581Y-164897D01*
X133835Y-164314D01*
X132525Y-162856D01*
X131651Y-161106D01*
X131433Y-159064D01*
X131651Y-157022D01*
X132525Y-155272D01*
X133835Y-153814D01*
X135581Y-153231D01*
X137109Y-153522D01*
X138201Y-154106D01*
X139293Y-155272D01*
G01X149588Y-157022D02*
X156575D01*
X155920Y-154980D01*
X154828Y-153814D01*
X153300Y-153231D01*
X151771Y-153522D01*
X150461Y-154397D01*
X149588Y-156439D01*
X149151Y-158189D01*
Y-159939D01*
X149588Y-161689D01*
X150680Y-163439D01*
X151990Y-164605D01*
X153518Y-164897D01*
X155046Y-164314D01*
X156575Y-162564D01*
G01X170363Y-164897D02*
Y-147397D01*
G01X376163Y-209897D02*
Y-192397D01*
X373543Y-195897D01*
G01Y-209897D02*
X378783D01*
G01X396283D02*
Y-192397D01*
X388204Y-204939D01*
X399122D01*
G01X406360Y-207273D02*
X407669Y-208731D01*
X409198Y-209605D01*
X411163Y-209897D01*
X413128Y-209314D01*
X414656Y-208147D01*
X415748Y-206106D01*
X415966Y-203772D01*
X415530Y-201439D01*
X414438Y-199980D01*
X412909Y-198814D01*
X411381Y-198522D01*
X409853Y-198814D01*
X407888Y-199980D01*
X408543Y-192397D01*
X414438D01*
G01X431283Y-209897D02*
Y-192397D01*
X423204Y-204939D01*
X434122D01*
G01X441360Y-207273D02*
X442669Y-208731D01*
X444198Y-209605D01*
X446163Y-209897D01*
X448128Y-209314D01*
X449656Y-208147D01*
X450748Y-206106D01*
X450966Y-203772D01*
X450530Y-201439D01*
X449438Y-199980D01*
X447909Y-198814D01*
X446381Y-198522D01*
X444853Y-198814D01*
X442888Y-199980D01*
X443543Y-192397D01*
X449438D01*
G01X363046Y-164897D02*
Y-147397D01*
X368286D01*
X370033Y-148272D01*
X371343Y-150314D01*
X371780Y-152647D01*
X371343Y-154980D01*
X370251Y-156730D01*
X368286Y-157606D01*
X363046D01*
G01X389716Y-148856D02*
X388406Y-147980D01*
X386878Y-147397D01*
X385131D01*
X383166Y-148272D01*
X381638Y-149730D01*
X380546Y-151481D01*
X379673Y-154397D01*
X379454Y-157022D01*
X379891Y-159647D01*
X380546Y-161397D01*
X381856Y-163147D01*
X383385Y-164314D01*
X384913Y-164897D01*
X386441D01*
X387970Y-164314D01*
X389280Y-163439D01*
X390372Y-162273D01*
G01X404159Y-155564D02*
X405033Y-154689D01*
X405688Y-153231D01*
X406125Y-151188D01*
X405688Y-149439D01*
X404815Y-148272D01*
X403286Y-147397D01*
X397391D01*
Y-164897D01*
X404596D01*
X406125Y-163731D01*
X406998Y-161980D01*
X407435Y-159939D01*
X406998Y-157897D01*
X405688Y-156147D01*
X404159Y-155564D01*
X397391D01*
G01X413363Y-170730D02*
X426463D01*
G01X432391Y-164897D02*
Y-147397D01*
X442435Y-164897D01*
Y-147397D01*
G01X454913Y-164897D02*
X453166Y-164605D01*
X451638Y-163439D01*
X450328Y-161689D01*
X449454Y-159647D01*
X449018Y-157314D01*
Y-154980D01*
X449454Y-152647D01*
X450328Y-150605D01*
X451638Y-148856D01*
X453166Y-147689D01*
X454913Y-147397D01*
X456659Y-147689D01*
X458188Y-148856D01*
X459498Y-150605D01*
X460372Y-152647D01*
X460808Y-154980D01*
Y-157314D01*
X460372Y-159647D01*
X459498Y-161689D01*
X458188Y-163439D01*
X456659Y-164605D01*
X454913Y-164897D01*
G01X505754Y-147397D02*
X511213Y-164897D01*
X516672Y-147397D01*
G01X533080Y-164897D02*
X524346D01*
Y-147397D01*
X533080D01*
G01X529586Y-155855D02*
X524346D01*
G01X541846Y-164897D02*
Y-147397D01*
X547305D01*
X549051Y-148272D01*
X550143Y-149439D01*
X550580Y-151772D01*
X550143Y-154106D01*
X548833Y-155564D01*
X547305Y-156439D01*
X541846D01*
G01X547305D02*
X550580Y-164897D01*
G01X563713Y-165480D02*
X563276Y-165189D01*
Y-164605D01*
X563713Y-164314D01*
X564150Y-164605D01*
Y-165189D01*
X563713Y-165480D01*
G01X524128Y-207564D02*
X525875Y-209022D01*
X527840Y-209897D01*
X529586D01*
X531333Y-209022D01*
X532643Y-207564D01*
X533298Y-205522D01*
X532861Y-203481D01*
X531770Y-201730D01*
X529805Y-200564D01*
X527185Y-199980D01*
X525656Y-198814D01*
X525001Y-196772D01*
X525438Y-194730D01*
X526530Y-193272D01*
X528058Y-192397D01*
X529586D01*
X531115Y-192980D01*
X532425Y-194439D01*
G01X540754Y-209897D02*
X546213Y-192397D01*
X551672Y-209897D01*
G01X549706Y-203772D02*
X542719D01*
G01X718030Y-192397D02*
Y-209897D01*
X709296D01*
G01X700966Y-207273D02*
X699657Y-208731D01*
X698128Y-209605D01*
X696163Y-209897D01*
X694198Y-209314D01*
X692670Y-208147D01*
X691578Y-206106D01*
X691360Y-203772D01*
X691796Y-201439D01*
X692888Y-199980D01*
X694417Y-198814D01*
X695945Y-198522D01*
X697473Y-198814D01*
X699438Y-199980D01*
X698783Y-192397D01*
X692888D01*
G01X684122D02*
X678663Y-209897D01*
X673204Y-192397D01*
G01X656360Y-193856D02*
X657670Y-192980D01*
X659198Y-192397D01*
X660945D01*
X662910Y-193272D01*
X664438Y-194730D01*
X665530Y-196481D01*
X666403Y-199397D01*
X666622Y-202022D01*
X666185Y-204647D01*
X665530Y-206397D01*
X664220Y-208147D01*
X662691Y-209314D01*
X661163Y-209897D01*
X659635D01*
X658106Y-209314D01*
X656796Y-208439D01*
X655704Y-207273D01*
G01X638860Y-193856D02*
X640170Y-192980D01*
X641698Y-192397D01*
X643445D01*
X645410Y-193272D01*
X646938Y-194730D01*
X648030Y-196481D01*
X648903Y-199397D01*
X649122Y-202022D01*
X648685Y-204647D01*
X648030Y-206397D01*
X646720Y-208147D01*
X645191Y-209314D01*
X643663Y-209897D01*
X642135D01*
X640606Y-209314D01*
X639296Y-208439D01*
X638204Y-207273D01*
G01X630546Y-147397D02*
Y-164897D01*
X639280D01*
G01X656343D02*
Y-153231D01*
G01Y-155272D02*
X655470Y-154106D01*
X654159Y-153522D01*
X652631Y-153231D01*
X651103Y-153814D01*
X649793Y-154980D01*
X648919Y-156730D01*
X648483Y-159064D01*
X648919Y-161397D01*
X649793Y-163147D01*
X651103Y-164314D01*
X652631Y-164897D01*
X654159Y-164605D01*
X655470Y-163731D01*
X656343Y-162564D01*
G01X665328Y-170147D02*
X666638Y-170730D01*
X668385Y-170147D01*
X669476Y-168981D01*
X670350Y-167522D01*
X671659Y-162856D01*
X674498Y-153231D01*
G01X667511D02*
X671659Y-162856D01*
G01X684138Y-157022D02*
X691125D01*
X690470Y-154980D01*
X689378Y-153814D01*
X687850Y-153231D01*
X686321Y-153522D01*
X685011Y-154397D01*
X684138Y-156439D01*
X683701Y-158189D01*
Y-159939D01*
X684138Y-161689D01*
X685230Y-163439D01*
X686540Y-164605D01*
X688068Y-164897D01*
X689596Y-164314D01*
X691125Y-162564D01*
G01X701856Y-164897D02*
Y-153231D01*
G01Y-155564D02*
X702948Y-154397D01*
X704040Y-153522D01*
X705568Y-153231D01*
X706659Y-153522D01*
X707970Y-154397D01*
G01X719138Y-162856D02*
X720230Y-164022D01*
X721758Y-164897D01*
X723068D01*
X724378Y-164314D01*
X725251Y-163439D01*
X725688Y-162273D01*
X725470Y-160522D01*
X724596Y-159647D01*
X720666Y-157897D01*
X719793Y-155855D01*
X720230Y-154397D01*
X721103Y-153522D01*
X722413Y-153231D01*
X723723Y-153522D01*
X725033Y-154397D01*
G01X790596Y-209897D02*
Y-192397D01*
X796055D01*
X797801Y-193272D01*
X798893Y-194439D01*
X799330Y-196772D01*
X798893Y-199106D01*
X797583Y-200564D01*
X796055Y-201439D01*
X790596D01*
G01X796055D02*
X799330Y-209897D01*
G01X809188Y-202022D02*
X816175D01*
X815520Y-199980D01*
X814428Y-198814D01*
X812900Y-198231D01*
X811371Y-198522D01*
X810061Y-199397D01*
X809188Y-201439D01*
X808751Y-203189D01*
Y-204939D01*
X809188Y-206689D01*
X810280Y-208439D01*
X811590Y-209605D01*
X813118Y-209897D01*
X814646Y-209314D01*
X816175Y-207564D01*
G01X826033Y-209897D02*
Y-192397D01*
G01Y-201147D02*
X827125Y-199397D01*
X828435Y-198522D01*
X829745Y-198231D01*
X831709Y-198814D01*
X833020Y-199980D01*
X833893Y-202022D01*
Y-204355D01*
X833456Y-206689D01*
X832583Y-208439D01*
X831055Y-209605D01*
X829745Y-209897D01*
X828435Y-209605D01*
X827125Y-208731D01*
X826033Y-207273D01*
G01X844188Y-202022D02*
X851175D01*
X850520Y-199980D01*
X849428Y-198814D01*
X847900Y-198231D01*
X846371Y-198522D01*
X845061Y-199397D01*
X844188Y-201439D01*
X843751Y-203189D01*
Y-204939D01*
X844188Y-206689D01*
X845280Y-208439D01*
X846590Y-209605D01*
X848118Y-209897D01*
X849646Y-209314D01*
X851175Y-207564D01*
G01X868456Y-199689D02*
X866928Y-198522D01*
X865618Y-198231D01*
X863871Y-198814D01*
X862561Y-199980D01*
X861688Y-202022D01*
X861469Y-204064D01*
X861688Y-206106D01*
X862561Y-207856D01*
X863871Y-209314D01*
X865618Y-209897D01*
X867146Y-209314D01*
X868456Y-208147D01*
G01X885956Y-199689D02*
X884428Y-198522D01*
X883118Y-198231D01*
X881371Y-198814D01*
X880061Y-199980D01*
X879188Y-202022D01*
X878969Y-204064D01*
X879188Y-206106D01*
X880061Y-207856D01*
X881371Y-209314D01*
X883118Y-209897D01*
X884646Y-209314D01*
X885956Y-208147D01*
G01X903893Y-209897D02*
Y-198231D01*
G01Y-200272D02*
X903020Y-199106D01*
X901709Y-198522D01*
X900181Y-198231D01*
X898653Y-198814D01*
X897343Y-199980D01*
X896469Y-201730D01*
X896033Y-204064D01*
X896469Y-206397D01*
X897343Y-208147D01*
X898653Y-209314D01*
X900181Y-209897D01*
X901709Y-209605D01*
X903020Y-208731D01*
X903893Y-207564D01*
G01X781410Y-164897D02*
Y-147397D01*
X785776D01*
X787523Y-148272D01*
X788833Y-149439D01*
X789925Y-151188D01*
X790798Y-153231D01*
X791016Y-156147D01*
X790798Y-159064D01*
X789925Y-161106D01*
X788833Y-162856D01*
X787523Y-164022D01*
X785776Y-164897D01*
X781410D01*
G01X800438Y-157022D02*
X807425D01*
X806770Y-154980D01*
X805678Y-153814D01*
X804150Y-153231D01*
X802621Y-153522D01*
X801311Y-154397D01*
X800438Y-156439D01*
X800001Y-158189D01*
Y-159939D01*
X800438Y-161689D01*
X801530Y-163439D01*
X802840Y-164605D01*
X804368Y-164897D01*
X805896Y-164314D01*
X807425Y-162564D01*
G01X817938Y-162856D02*
X819030Y-164022D01*
X820558Y-164897D01*
X821868D01*
X823178Y-164314D01*
X824051Y-163439D01*
X824488Y-162273D01*
X824270Y-160522D01*
X823396Y-159647D01*
X819466Y-157897D01*
X818593Y-155855D01*
X819030Y-154397D01*
X819903Y-153522D01*
X821213Y-153231D01*
X822523Y-153522D01*
X823833Y-154397D01*
G01X838713Y-153231D02*
Y-164897D01*
G01Y-148564D02*
X838276Y-148272D01*
Y-147689D01*
X838713Y-147397D01*
X839150Y-147689D01*
Y-148272D01*
X838713Y-148564D01*
G01X853156Y-169272D02*
X854685Y-170439D01*
X856431Y-170730D01*
X857959Y-170439D01*
X859270Y-168981D01*
X860143Y-166939D01*
Y-153231D01*
G01Y-155564D02*
X859270Y-154397D01*
X857959Y-153522D01*
X856431Y-153231D01*
X854685Y-153814D01*
X853593Y-154980D01*
X852719Y-157022D01*
X852283Y-159064D01*
X852501Y-160814D01*
X853375Y-162856D01*
X854685Y-164314D01*
X856431Y-164897D01*
X857741Y-164605D01*
X859270Y-163439D01*
X860143Y-162273D01*
G01X870001Y-164897D02*
Y-153231D01*
G01Y-156147D02*
X870875Y-154689D01*
X872185Y-153522D01*
X873931Y-153231D01*
X875459Y-153522D01*
X876770Y-154689D01*
X877425Y-156730D01*
Y-164897D01*
G01X887938Y-157022D02*
X894925D01*
X894270Y-154980D01*
X893178Y-153814D01*
X891650Y-153231D01*
X890121Y-153522D01*
X888811Y-154397D01*
X887938Y-156439D01*
X887501Y-158189D01*
Y-159939D01*
X887938Y-161689D01*
X889030Y-163439D01*
X890340Y-164605D01*
X891868Y-164897D01*
X893396Y-164314D01*
X894925Y-162564D01*
G01X905656Y-164897D02*
Y-153231D01*
G01Y-155564D02*
X906748Y-154397D01*
X907840Y-153522D01*
X909368Y-153231D01*
X910459Y-153522D01*
X911770Y-154397D01*
G01X952413Y-192397D02*
X950666Y-192980D01*
X949356Y-194439D01*
X948483Y-196188D01*
X947828Y-198522D01*
X947610Y-201147D01*
X947828Y-203772D01*
X948483Y-206106D01*
X949356Y-207856D01*
X950666Y-209314D01*
X952413Y-209897D01*
X954159Y-209314D01*
X955470Y-207856D01*
X956343Y-206106D01*
X956998Y-203772D01*
X957216Y-201147D01*
X956998Y-198522D01*
X956343Y-196188D01*
X955470Y-194439D01*
X954159Y-192980D01*
X952413Y-192397D01*
G01X969913Y-209897D02*
X971441Y-209605D01*
X973188Y-208731D01*
X974280Y-207273D01*
X974716Y-205230D01*
X974280Y-203189D01*
X972970Y-201439D01*
X971005Y-200564D01*
X968821D01*
X967511Y-199980D01*
X966419Y-198522D01*
X965983Y-196481D01*
X966638Y-194439D01*
X968166Y-192980D01*
X969913Y-192397D01*
X971659Y-192980D01*
X973188Y-194439D01*
X973843Y-196481D01*
X973406Y-198522D01*
X972315Y-199980D01*
X971005Y-200564D01*
X968821D01*
X966856Y-201439D01*
X965546Y-203189D01*
X965110Y-205230D01*
X965546Y-207273D01*
X966638Y-208731D01*
X968385Y-209605D01*
X969913Y-209897D01*
G01X983483Y-210480D02*
X991343Y-192397D01*
G01X1004913D02*
X1003166Y-192980D01*
X1001856Y-194439D01*
X1000983Y-196188D01*
X1000328Y-198522D01*
X1000110Y-201147D01*
X1000328Y-203772D01*
X1000983Y-206106D01*
X1001856Y-207856D01*
X1003166Y-209314D01*
X1004913Y-209897D01*
X1006659Y-209314D01*
X1007970Y-207856D01*
X1008843Y-206106D01*
X1009498Y-203772D01*
X1009716Y-201147D01*
X1009498Y-198522D01*
X1008843Y-196188D01*
X1007970Y-194439D01*
X1006659Y-192980D01*
X1004913Y-192397D01*
G01X1022413Y-209897D02*
Y-192397D01*
X1019793Y-195897D01*
G01Y-209897D02*
X1025033D01*
G01X1035983Y-210480D02*
X1043843Y-192397D01*
G01X1053265Y-195314D02*
X1054575Y-193564D01*
X1056103Y-192689D01*
X1057850Y-192397D01*
X1060033Y-192980D01*
X1061561Y-194439D01*
X1061998Y-196188D01*
X1061780Y-197939D01*
X1060906Y-199397D01*
X1056540Y-202314D01*
X1054575Y-204355D01*
X1053265Y-207273D01*
X1052828Y-209897D01*
X1061998D01*
G01X1074913Y-192397D02*
X1073166Y-192980D01*
X1071856Y-194439D01*
X1070983Y-196188D01*
X1070328Y-198522D01*
X1070110Y-201147D01*
X1070328Y-203772D01*
X1070983Y-206106D01*
X1071856Y-207856D01*
X1073166Y-209314D01*
X1074913Y-209897D01*
X1076659Y-209314D01*
X1077970Y-207856D01*
X1078843Y-206106D01*
X1079498Y-203772D01*
X1079716Y-201147D01*
X1079498Y-198522D01*
X1078843Y-196188D01*
X1077970Y-194439D01*
X1076659Y-192980D01*
X1074913Y-192397D01*
G01X1092413Y-209897D02*
Y-192397D01*
X1089793Y-195897D01*
G01Y-209897D02*
X1095033D01*
G01X1112533D02*
Y-192397D01*
X1104454Y-204939D01*
X1115372D01*
G01X1000110Y-164897D02*
Y-147397D01*
X1004476D01*
X1006223Y-148272D01*
X1007533Y-149439D01*
X1008625Y-151188D01*
X1009498Y-153231D01*
X1009716Y-156147D01*
X1009498Y-159064D01*
X1008625Y-161106D01*
X1007533Y-162856D01*
X1006223Y-164022D01*
X1004476Y-164897D01*
X1000110D01*
G01X1026343D02*
Y-153231D01*
G01Y-155272D02*
X1025470Y-154106D01*
X1024159Y-153522D01*
X1022631Y-153231D01*
X1021103Y-153814D01*
X1019793Y-154980D01*
X1018919Y-156730D01*
X1018483Y-159064D01*
X1018919Y-161397D01*
X1019793Y-163147D01*
X1021103Y-164314D01*
X1022631Y-164897D01*
X1024159Y-164605D01*
X1025470Y-163731D01*
X1026343Y-162564D01*
G01X1039913Y-147397D02*
Y-164897D01*
G01X1036856Y-153231D02*
X1042970D01*
G01X1054138Y-157022D02*
X1061125D01*
X1060470Y-154980D01*
X1059378Y-153814D01*
X1057850Y-153231D01*
X1056321Y-153522D01*
X1055011Y-154397D01*
X1054138Y-156439D01*
X1053701Y-158189D01*
Y-159939D01*
X1054138Y-161689D01*
X1055230Y-163439D01*
X1056540Y-164605D01*
X1058068Y-164897D01*
X1059596Y-164314D01*
X1061125Y-162564D01*
M02*
